FILE_TYPE = MACRO_DRAWING;
SET COLOR_WIRE YELLOW;
SET COLOR_PROP ORANGE;
SET COLOR_DOT WHITE;
SET COLOR_ARC YELLOW;
SET COLOR_BODY GREEN;
SET COLOR_NOTE PURPLE;
SET PROP_DISPLAY VALUE;
SET PAGE_NUMBER P15;
FORCEADD GENOA_SP5..6
(-4650 3600);
FORCEPROP 1 LAST LOCATION U25
J 0
(-5295 6431);
DISPLAY 0.489362 (-5295 6431);
PAINT SKYBLUE (-5295 6431);
FORCEPROP 0 LAST $SEC 6
J 0
(-5275 6475);
DISPLAY 0.680851 (-5275 6475);
PAINT MONO (-5275 6475);
DISPLAY INVISIBLE (-5275 6475);
FORCEPROP 0 LAST CDS_SEC 6
J 0
(-5300 6400);
DISPLAY 1.021277 (-5300 6400);
DISPLAY INVISIBLE (-5300 6400);
FORCEPROP 0 LASTPIN (-5450 2975) $PN BC67
J 2
(-5460 2985);
DISPLAY 0.489362 (-5460 2985);
PAINT MONO (-5460 2985);
FORCEPROP 0 LASTPIN (-5450 2925) $PN BD67
J 2
(-5460 2935);
DISPLAY 0.489362 (-5460 2935);
PAINT MONO (-5460 2935);
FORCEPROP 0 LASTPIN (-5450 1825) $PN BF67
J 2
(-5460 1835);
DISPLAY 0.489362 (-5460 1835);
PAINT MONO (-5460 1835);
FORCEPROP 0 LASTPIN (-5450 1775) $PN BG67
J 2
(-5460 1785);
DISPLAY 0.489362 (-5460 1785);
PAINT MONO (-5460 1785);
FORCEPROP 0 LASTPIN (-5450 2125) $PN AT65
J 2
(-5460 2135);
DISPLAY 0.489362 (-5460 2135);
PAINT MONO (-5460 2135);
FORCEPROP 0 LASTPIN (-5450 2025) $PN AU66
J 2
(-5460 2035);
DISPLAY 0.489362 (-5460 2035);
PAINT MONO (-5460 2035);
FORCEPROP 0 LASTPIN (-5450 2825) $PN AV67
J 2
(-5460 2835);
DISPLAY 0.489362 (-5460 2835);
PAINT MONO (-5460 2835);
FORCEPROP 0 LASTPIN (-5450 2775) $PN AW66
J 2
(-5460 2785);
DISPLAY 0.489362 (-5460 2785);
PAINT MONO (-5460 2785);
FORCEPROP 0 LASTPIN (-5450 2675) $PN BN66
J 2
(-5460 2685);
DISPLAY 0.489362 (-5460 2685);
PAINT MONO (-5460 2685);
FORCEPROP 0 LASTPIN (-5450 1675) $PN AU67
J 2
(-5460 1685);
DISPLAY 0.489362 (-5460 1685);
PAINT MONO (-5460 1685);
FORCEPROP 0 LASTPIN (-5450 1625) $PN AV65
J 2
(-5460 1635);
DISPLAY 0.489362 (-5460 1635);
PAINT MONO (-5460 1635);
FORCEPROP 0 LASTPIN (-5450 1525) $PN BP65
J 2
(-5460 1535);
DISPLAY 0.489362 (-5460 1535);
PAINT MONO (-5460 1535);
FORCEPROP 0 LASTPIN (-5450 3825) $PN AW67
J 2
(-5460 3835);
DISPLAY 0.489362 (-5460 3835);
PAINT MONO (-5460 3835);
FORCEPROP 0 LASTPIN (-5450 3775) $PN AY67
J 2
(-5460 3785);
DISPLAY 0.489362 (-5460 3785);
PAINT MONO (-5460 3785);
FORCEPROP 0 LASTPIN (-5450 3725) $PN AY65
J 2
(-5460 3735);
DISPLAY 0.489362 (-5460 3735);
PAINT MONO (-5460 3735);
FORCEPROP 0 LASTPIN (-5450 3675) $PN BA66
J 2
(-5460 3685);
DISPLAY 0.489362 (-5460 3685);
PAINT MONO (-5460 3685);
FORCEPROP 0 LASTPIN (-5450 3625) $PN BA67
J 2
(-5460 3635);
DISPLAY 0.489362 (-5460 3635);
PAINT MONO (-5460 3635);
FORCEPROP 0 LASTPIN (-5450 3575) $PN BB67
J 2
(-5460 3585);
DISPLAY 0.489362 (-5460 3585);
PAINT MONO (-5460 3585);
FORCEPROP 0 LASTPIN (-5450 3525) $PN BB65
J 2
(-5460 3535);
DISPLAY 0.489362 (-5460 3535);
PAINT MONO (-5460 3535);
FORCEPROP 0 LASTPIN (-3850 2375) $PN AJ67
J 0
(-3840 2385);
DISPLAY 0.489362 (-3840 2385);
PAINT MONO (-3840 2385);
FORCEPROP 0 LASTPIN (-3850 2325) $PN AK65
J 0
(-3840 2335);
DISPLAY 0.489362 (-3840 2335);
PAINT MONO (-3840 2335);
FORCEPROP 0 LASTPIN (-3850 2275) $PN AK67
J 0
(-3840 2285);
DISPLAY 0.489362 (-3840 2285);
PAINT MONO (-3840 2285);
FORCEPROP 0 LASTPIN (-3850 2225) $PN AL66
J 0
(-3840 2235);
DISPLAY 0.489362 (-3840 2235);
PAINT MONO (-3840 2235);
FORCEPROP 0 LASTPIN (-3850 2175) $PN AN67
J 0
(-3840 2185);
DISPLAY 0.489362 (-3840 2185);
PAINT MONO (-3840 2185);
FORCEPROP 0 LASTPIN (-3850 2125) $PN AP65
J 0
(-3840 2135);
DISPLAY 0.489362 (-3840 2135);
PAINT MONO (-3840 2135);
FORCEPROP 0 LASTPIN (-3850 2075) $PN AP67
J 0
(-3840 2085);
DISPLAY 0.489362 (-3840 2085);
PAINT MONO (-3840 2085);
FORCEPROP 0 LASTPIN (-3850 2025) $PN AR66
J 0
(-3840 2035);
DISPLAY 0.489362 (-3840 2035);
PAINT MONO (-3840 2035);
FORCEPROP 0 LASTPIN (-3850 5975) $PN E67
J 0
(-3840 5985);
DISPLAY 0.489362 (-3840 5985);
PAINT MONO (-3840 5985);
FORCEPROP 0 LASTPIN (-3850 5925) $PN F65
J 0
(-3840 5935);
DISPLAY 0.489362 (-3840 5935);
PAINT MONO (-3840 5935);
FORCEPROP 0 LASTPIN (-3850 5875) $PN F67
J 0
(-3840 5885);
DISPLAY 0.489362 (-3840 5885);
PAINT MONO (-3840 5885);
FORCEPROP 0 LASTPIN (-3850 5825) $PN G66
J 0
(-3840 5835);
DISPLAY 0.489362 (-3840 5835);
PAINT MONO (-3840 5835);
FORCEPROP 0 LASTPIN (-3850 5775) $PN J67
J 0
(-3840 5785);
DISPLAY 0.489362 (-3840 5785);
PAINT MONO (-3840 5785);
FORCEPROP 0 LASTPIN (-3850 5725) $PN K65
J 0
(-3840 5735);
DISPLAY 0.489362 (-3840 5735);
PAINT MONO (-3840 5735);
FORCEPROP 0 LASTPIN (-3850 5675) $PN K67
J 0
(-3840 5685);
DISPLAY 0.489362 (-3840 5685);
PAINT MONO (-3840 5685);
FORCEPROP 0 LASTPIN (-3850 5625) $PN L66
J 0
(-3840 5635);
DISPLAY 0.489362 (-3840 5635);
PAINT MONO (-3840 5635);
FORCEPROP 0 LASTPIN (-3850 5525) $PN L67
J 0
(-3840 5535);
DISPLAY 0.489362 (-3840 5535);
PAINT MONO (-3840 5535);
FORCEPROP 0 LASTPIN (-3850 5475) $PN M65
J 0
(-3840 5485);
DISPLAY 0.489362 (-3840 5485);
PAINT MONO (-3840 5485);
FORCEPROP 0 LASTPIN (-3850 5425) $PN M67
J 0
(-3840 5435);
DISPLAY 0.489362 (-3840 5435);
PAINT MONO (-3840 5435);
FORCEPROP 0 LASTPIN (-3850 5375) $PN N66
J 0
(-3840 5385);
DISPLAY 0.489362 (-3840 5385);
PAINT MONO (-3840 5385);
FORCEPROP 0 LASTPIN (-3850 5325) $PN R67
J 0
(-3840 5335);
DISPLAY 0.489362 (-3840 5335);
PAINT MONO (-3840 5335);
FORCEPROP 0 LASTPIN (-3850 5275) $PN T65
J 0
(-3840 5285);
DISPLAY 0.489362 (-3840 5285);
PAINT MONO (-3840 5285);
FORCEPROP 0 LASTPIN (-3850 5225) $PN T67
J 0
(-3840 5235);
DISPLAY 0.489362 (-3840 5235);
PAINT MONO (-3840 5235);
FORCEPROP 0 LASTPIN (-3850 5175) $PN U66
J 0
(-3840 5185);
DISPLAY 0.489362 (-3840 5185);
PAINT MONO (-3840 5185);
FORCEPROP 0 LASTPIN (-3850 5075) $PN U67
J 0
(-3840 5085);
DISPLAY 0.489362 (-3840 5085);
PAINT MONO (-3840 5085);
FORCEPROP 0 LASTPIN (-3850 5025) $PN V65
J 0
(-3840 5035);
DISPLAY 0.489362 (-3840 5035);
PAINT MONO (-3840 5035);
FORCEPROP 0 LASTPIN (-3850 4975) $PN V67
J 0
(-3840 4985);
DISPLAY 0.489362 (-3840 4985);
PAINT MONO (-3840 4985);
FORCEPROP 0 LASTPIN (-3850 4925) $PN W66
J 0
(-3840 4935);
DISPLAY 0.489362 (-3840 4935);
PAINT MONO (-3840 4935);
FORCEPROP 0 LASTPIN (-3850 4875) $PN AA67
J 0
(-3840 4885);
DISPLAY 0.489362 (-3840 4885);
PAINT MONO (-3840 4885);
FORCEPROP 0 LASTPIN (-3850 4825) $PN AB65
J 0
(-3840 4835);
DISPLAY 0.489362 (-3840 4835);
PAINT MONO (-3840 4835);
FORCEPROP 0 LASTPIN (-3850 4775) $PN AB67
J 0
(-3840 4785);
DISPLAY 0.489362 (-3840 4785);
PAINT MONO (-3840 4785);
FORCEPROP 0 LASTPIN (-3850 4725) $PN AC66
J 0
(-3840 4735);
DISPLAY 0.489362 (-3840 4735);
PAINT MONO (-3840 4735);
FORCEPROP 0 LASTPIN (-3850 4625) $PN AC67
J 0
(-3840 4635);
DISPLAY 0.489362 (-3840 4635);
PAINT MONO (-3840 4635);
FORCEPROP 0 LASTPIN (-3850 4575) $PN AD65
J 0
(-3840 4585);
DISPLAY 0.489362 (-3840 4585);
PAINT MONO (-3840 4585);
FORCEPROP 0 LASTPIN (-3850 4525) $PN AD67
J 0
(-3840 4535);
DISPLAY 0.489362 (-3840 4535);
PAINT MONO (-3840 4535);
FORCEPROP 0 LASTPIN (-3850 4475) $PN AE66
J 0
(-3840 4485);
DISPLAY 0.489362 (-3840 4485);
PAINT MONO (-3840 4485);
FORCEPROP 0 LASTPIN (-3850 4425) $PN AG67
J 0
(-3840 4435);
DISPLAY 0.489362 (-3840 4435);
PAINT MONO (-3840 4435);
FORCEPROP 0 LASTPIN (-3850 4375) $PN AH65
J 0
(-3840 4385);
DISPLAY 0.489362 (-3840 4385);
PAINT MONO (-3840 4385);
FORCEPROP 0 LASTPIN (-3850 4325) $PN AH67
J 0
(-3840 4335);
DISPLAY 0.489362 (-3840 4335);
PAINT MONO (-3840 4335);
FORCEPROP 0 LASTPIN (-3850 4275) $PN AJ66
J 0
(-3840 4285);
DISPLAY 0.489362 (-3840 4285);
PAINT MONO (-3840 4285);
FORCEPROP 0 LASTPIN (-5450 5975) $PN G67
J 2
(-5460 5985);
DISPLAY 0.489362 (-5460 5985);
PAINT MONO (-5460 5985);
FORCEPROP 0 LASTPIN (-5450 5875) $PN N67
J 2
(-5460 5885);
DISPLAY 0.489362 (-5460 5885);
PAINT MONO (-5460 5885);
FORCEPROP 0 LASTPIN (-5450 5775) $PN W67
J 2
(-5460 5785);
DISPLAY 0.489362 (-5460 5785);
PAINT MONO (-5460 5785);
FORCEPROP 0 LASTPIN (-5450 5675) $PN AE67
J 2
(-5460 5685);
DISPLAY 0.489362 (-5460 5685);
PAINT MONO (-5460 5685);
FORCEPROP 0 LASTPIN (-5450 5575) $PN AL67
J 2
(-5460 5585);
DISPLAY 0.489362 (-5460 5585);
PAINT MONO (-5460 5585);
FORCEPROP 0 LASTPIN (-5450 5475) $PN J66
J 2
(-5460 5485);
DISPLAY 0.489362 (-5460 5485);
PAINT MONO (-5460 5485);
FORCEPROP 0 LASTPIN (-5450 5375) $PN R66
J 2
(-5460 5385);
DISPLAY 0.489362 (-5460 5385);
PAINT MONO (-5460 5385);
FORCEPROP 0 LASTPIN (-5450 5275) $PN AA66
J 2
(-5460 5285);
DISPLAY 0.489362 (-5460 5285);
PAINT MONO (-5460 5285);
FORCEPROP 0 LASTPIN (-5450 5175) $PN AG66
J 2
(-5460 5185);
DISPLAY 0.489362 (-5460 5185);
PAINT MONO (-5460 5185);
FORCEPROP 0 LASTPIN (-5450 5075) $PN AN66
J 2
(-5460 5085);
DISPLAY 0.489362 (-5460 5085);
PAINT MONO (-5460 5085);
FORCEPROP 0 LASTPIN (-5450 5925) $PN H67
J 2
(-5460 5935);
DISPLAY 0.489362 (-5460 5935);
PAINT MONO (-5460 5935);
FORCEPROP 0 LASTPIN (-5450 5825) $PN P67
J 2
(-5460 5835);
DISPLAY 0.489362 (-5460 5835);
PAINT MONO (-5460 5835);
FORCEPROP 0 LASTPIN (-5450 5725) $PN Y67
J 2
(-5460 5735);
DISPLAY 0.489362 (-5460 5735);
PAINT MONO (-5460 5735);
FORCEPROP 0 LASTPIN (-5450 5625) $PN AF67
J 2
(-5460 5635);
DISPLAY 0.489362 (-5460 5635);
PAINT MONO (-5460 5635);
FORCEPROP 0 LASTPIN (-5450 5525) $PN AM67
J 2
(-5460 5535);
DISPLAY 0.489362 (-5460 5535);
PAINT MONO (-5460 5535);
FORCEPROP 0 LASTPIN (-5450 5425) $PN H65
J 2
(-5460 5435);
DISPLAY 0.489362 (-5460 5435);
PAINT MONO (-5460 5435);
FORCEPROP 0 LASTPIN (-5450 5325) $PN P65
J 2
(-5460 5335);
DISPLAY 0.489362 (-5460 5335);
PAINT MONO (-5460 5335);
FORCEPROP 0 LASTPIN (-5450 5225) $PN Y65
J 2
(-5460 5235);
DISPLAY 0.489362 (-5460 5235);
PAINT MONO (-5460 5235);
FORCEPROP 0 LASTPIN (-5450 5125) $PN AF65
J 2
(-5460 5135);
DISPLAY 0.489362 (-5460 5135);
PAINT MONO (-5460 5135);
FORCEPROP 0 LASTPIN (-5450 5025) $PN AM65
J 2
(-5460 5035);
DISPLAY 0.489362 (-5460 5035);
PAINT MONO (-5460 5035);
FORCEPROP 0 LASTPIN (-5450 2575) $PN BC66
J 2
(-5460 2585);
DISPLAY 0.489362 (-5460 2585);
PAINT MONO (-5460 2585);
FORCEPROP 0 LASTPIN (-5450 2475) $PN BM65
J 2
(-5460 2485);
DISPLAY 0.489362 (-5460 2485);
PAINT MONO (-5460 2485);
FORCEPROP 0 LASTPIN (-5450 2425) $PN BN67
J 2
(-5460 2435);
DISPLAY 0.489362 (-5460 2435);
PAINT MONO (-5460 2435);
FORCEPROP 0 LASTPIN (-5450 2325) $PN BP67
J 2
(-5460 2335);
DISPLAY 0.489362 (-5460 2335);
PAINT MONO (-5460 2335);
FORCEPROP 0 LASTPIN (-5450 1425) $PN BL66
J 2
(-5460 1435);
DISPLAY 0.489362 (-5460 1435);
PAINT MONO (-5460 1435);
FORCEPROP 0 LASTPIN (-5450 1375) $PN BM67
J 2
(-5460 1385);
DISPLAY 0.489362 (-5460 1385);
PAINT MONO (-5460 1385);
FORCEPROP 0 LASTPIN (-5450 1275) $PN BR67
J 2
(-5460 1285);
DISPLAY 0.489362 (-5460 1285);
PAINT MONO (-5460 1285);
FORCEPROP 0 LASTPIN (-5450 3425) $PN BG66
J 2
(-5460 3435);
DISPLAY 0.489362 (-5460 3435);
PAINT MONO (-5460 3435);
FORCEPROP 0 LASTPIN (-5450 3375) $PN BH65
J 2
(-5460 3385);
DISPLAY 0.489362 (-5460 3385);
PAINT MONO (-5460 3385);
FORCEPROP 0 LASTPIN (-5450 3325) $PN BH67
J 2
(-5460 3335);
DISPLAY 0.489362 (-5460 3335);
PAINT MONO (-5460 3335);
FORCEPROP 0 LASTPIN (-5450 3275) $PN BJ67
J 2
(-5460 3285);
DISPLAY 0.489362 (-5460 3285);
PAINT MONO (-5460 3285);
FORCEPROP 0 LASTPIN (-5450 3225) $PN BJ66
J 2
(-5460 3235);
DISPLAY 0.489362 (-5460 3235);
PAINT MONO (-5460 3235);
FORCEPROP 0 LASTPIN (-5450 3175) $PN BK65
J 2
(-5460 3185);
DISPLAY 0.489362 (-5460 3185);
PAINT MONO (-5460 3185);
FORCEPROP 0 LASTPIN (-5450 3125) $PN BK67
J 2
(-5460 3135);
DISPLAY 0.489362 (-5460 3135);
PAINT MONO (-5460 3135);
FORCEPROP 0 LASTPIN (-3850 1925) $PN BY67
J 0
(-3840 1935);
DISPLAY 0.489362 (-3840 1935);
PAINT MONO (-3840 1935);
FORCEPROP 0 LASTPIN (-3850 1875) $PN CA66
J 0
(-3840 1885);
DISPLAY 0.489362 (-3840 1885);
PAINT MONO (-3840 1885);
FORCEPROP 0 LASTPIN (-3850 1825) $PN CA67
J 0
(-3840 1835);
DISPLAY 0.489362 (-3840 1835);
PAINT MONO (-3840 1835);
FORCEPROP 0 LASTPIN (-3850 1775) $PN CB65
J 0
(-3840 1785);
DISPLAY 0.489362 (-3840 1785);
PAINT MONO (-3840 1785);
FORCEPROP 0 LASTPIN (-3850 1725) $PN BT67
J 0
(-3840 1735);
DISPLAY 0.489362 (-3840 1735);
PAINT MONO (-3840 1735);
FORCEPROP 0 LASTPIN (-3850 1675) $PN BU66
J 0
(-3840 1685);
DISPLAY 0.489362 (-3840 1685);
PAINT MONO (-3840 1685);
FORCEPROP 0 LASTPIN (-3850 1625) $PN BU67
J 0
(-3840 1635);
DISPLAY 0.489362 (-3840 1635);
PAINT MONO (-3840 1635);
FORCEPROP 0 LASTPIN (-3850 1575) $PN BV65
J 0
(-3840 1585);
DISPLAY 0.489362 (-3840 1585);
PAINT MONO (-3840 1585);
FORCEPROP 0 LASTPIN (-3850 4175) $PN CB67
J 0
(-3840 4185);
DISPLAY 0.489362 (-3840 4185);
PAINT MONO (-3840 4185);
FORCEPROP 0 LASTPIN (-3850 4125) $PN CC66
J 0
(-3840 4135);
DISPLAY 0.489362 (-3840 4135);
PAINT MONO (-3840 4135);
FORCEPROP 0 LASTPIN (-3850 4075) $PN CC67
J 0
(-3840 4085);
DISPLAY 0.489362 (-3840 4085);
PAINT MONO (-3840 4085);
FORCEPROP 0 LASTPIN (-3850 4025) $PN CD65
J 0
(-3840 4035);
DISPLAY 0.489362 (-3840 4035);
PAINT MONO (-3840 4035);
FORCEPROP 0 LASTPIN (-3850 3975) $PN CF67
J 0
(-3840 3985);
DISPLAY 0.489362 (-3840 3985);
PAINT MONO (-3840 3985);
FORCEPROP 0 LASTPIN (-3850 3925) $PN CG66
J 0
(-3840 3935);
DISPLAY 0.489362 (-3840 3935);
PAINT MONO (-3840 3935);
FORCEPROP 0 LASTPIN (-3850 3875) $PN CG67
J 0
(-3840 3885);
DISPLAY 0.489362 (-3840 3885);
PAINT MONO (-3840 3885);
FORCEPROP 0 LASTPIN (-3850 3825) $PN CH65
J 0
(-3840 3835);
DISPLAY 0.489362 (-3840 3835);
PAINT MONO (-3840 3835);
FORCEPROP 0 LASTPIN (-3850 3725) $PN CH67
J 0
(-3840 3735);
DISPLAY 0.489362 (-3840 3735);
PAINT MONO (-3840 3735);
FORCEPROP 0 LASTPIN (-3850 3675) $PN CJ66
J 0
(-3840 3685);
DISPLAY 0.489362 (-3840 3685);
PAINT MONO (-3840 3685);
FORCEPROP 0 LASTPIN (-3850 3625) $PN CJ67
J 0
(-3840 3635);
DISPLAY 0.489362 (-3840 3635);
PAINT MONO (-3840 3635);
FORCEPROP 0 LASTPIN (-3850 3575) $PN CK65
J 0
(-3840 3585);
DISPLAY 0.489362 (-3840 3585);
PAINT MONO (-3840 3585);
FORCEPROP 0 LASTPIN (-3850 3525) $PN CM67
J 0
(-3840 3535);
DISPLAY 0.489362 (-3840 3535);
PAINT MONO (-3840 3535);
FORCEPROP 0 LASTPIN (-3850 3475) $PN CN66
J 0
(-3840 3485);
DISPLAY 0.489362 (-3840 3485);
PAINT MONO (-3840 3485);
FORCEPROP 0 LASTPIN (-3850 3425) $PN CN67
J 0
(-3840 3435);
DISPLAY 0.489362 (-3840 3435);
PAINT MONO (-3840 3435);
FORCEPROP 0 LASTPIN (-3850 3375) $PN CP65
J 0
(-3840 3385);
DISPLAY 0.489362 (-3840 3385);
PAINT MONO (-3840 3385);
FORCEPROP 0 LASTPIN (-3850 3275) $PN CP67
J 0
(-3840 3285);
DISPLAY 0.489362 (-3840 3285);
PAINT MONO (-3840 3285);
FORCEPROP 0 LASTPIN (-3850 3225) $PN CR66
J 0
(-3840 3235);
DISPLAY 0.489362 (-3840 3235);
PAINT MONO (-3840 3235);
FORCEPROP 0 LASTPIN (-3850 3175) $PN CR67
J 0
(-3840 3185);
DISPLAY 0.489362 (-3840 3185);
PAINT MONO (-3840 3185);
FORCEPROP 0 LASTPIN (-3850 3125) $PN CT65
J 0
(-3840 3135);
DISPLAY 0.489362 (-3840 3135);
PAINT MONO (-3840 3135);
FORCEPROP 0 LASTPIN (-3850 3075) $PN CV67
J 0
(-3840 3085);
DISPLAY 0.489362 (-3840 3085);
PAINT MONO (-3840 3085);
FORCEPROP 0 LASTPIN (-3850 3025) $PN CW66
J 0
(-3840 3035);
DISPLAY 0.489362 (-3840 3035);
PAINT MONO (-3840 3035);
FORCEPROP 0 LASTPIN (-3850 2975) $PN CW67
J 0
(-3840 2985);
DISPLAY 0.489362 (-3840 2985);
PAINT MONO (-3840 2985);
FORCEPROP 0 LASTPIN (-3850 2925) $PN CY65
J 0
(-3840 2935);
DISPLAY 0.489362 (-3840 2935);
PAINT MONO (-3840 2935);
FORCEPROP 0 LASTPIN (-3850 2825) $PN CY67
J 0
(-3840 2835);
DISPLAY 0.489362 (-3840 2835);
PAINT MONO (-3840 2835);
FORCEPROP 0 LASTPIN (-3850 2775) $PN DA66
J 0
(-3840 2785);
DISPLAY 0.489362 (-3840 2785);
PAINT MONO (-3840 2785);
FORCEPROP 0 LASTPIN (-3850 2725) $PN DA67
J 0
(-3840 2735);
DISPLAY 0.489362 (-3840 2735);
PAINT MONO (-3840 2735);
FORCEPROP 0 LASTPIN (-3850 2675) $PN DB65
J 0
(-3840 2685);
DISPLAY 0.489362 (-3840 2685);
PAINT MONO (-3840 2685);
FORCEPROP 0 LASTPIN (-3850 2625) $PN DD67
J 0
(-3840 2635);
DISPLAY 0.489362 (-3840 2635);
PAINT MONO (-3840 2635);
FORCEPROP 0 LASTPIN (-3850 2575) $PN DE66
J 0
(-3840 2585);
DISPLAY 0.489362 (-3840 2585);
PAINT MONO (-3840 2585);
FORCEPROP 0 LASTPIN (-3850 2525) $PN DE67
J 0
(-3840 2535);
DISPLAY 0.489362 (-3840 2535);
PAINT MONO (-3840 2535);
FORCEPROP 0 LASTPIN (-3850 2475) $PN DF67
J 0
(-3840 2485);
DISPLAY 0.489362 (-3840 2485);
PAINT MONO (-3840 2485);
FORCEPROP 0 LASTPIN (-5450 4925) $PN CD67
J 2
(-5460 4935);
DISPLAY 0.489362 (-5460 4935);
PAINT MONO (-5460 4935);
FORCEPROP 0 LASTPIN (-5450 4825) $PN CK67
J 2
(-5460 4835);
DISPLAY 0.489362 (-5460 4835);
PAINT MONO (-5460 4835);
FORCEPROP 0 LASTPIN (-5450 4725) $PN CT67
J 2
(-5460 4735);
DISPLAY 0.489362 (-5460 4735);
PAINT MONO (-5460 4735);
FORCEPROP 0 LASTPIN (-5450 4625) $PN DB67
J 2
(-5460 4635);
DISPLAY 0.489362 (-5460 4635);
PAINT MONO (-5460 4635);
FORCEPROP 0 LASTPIN (-5450 4525) $PN BY65
J 2
(-5460 4535);
DISPLAY 0.489362 (-5460 4535);
PAINT MONO (-5460 4535);
FORCEPROP 0 LASTPIN (-5450 4425) $PN CF65
J 2
(-5460 4435);
DISPLAY 0.489362 (-5460 4435);
PAINT MONO (-5460 4435);
FORCEPROP 0 LASTPIN (-5450 4325) $PN CM65
J 2
(-5460 4335);
DISPLAY 0.489362 (-5460 4335);
PAINT MONO (-5460 4335);
FORCEPROP 0 LASTPIN (-5450 4225) $PN CV65
J 2
(-5460 4235);
DISPLAY 0.489362 (-5460 4235);
PAINT MONO (-5460 4235);
FORCEPROP 0 LASTPIN (-5450 4125) $PN DD65
J 2
(-5460 4135);
DISPLAY 0.489362 (-5460 4135);
PAINT MONO (-5460 4135);
FORCEPROP 0 LASTPIN (-5450 4025) $PN BV67
J 2
(-5460 4035);
DISPLAY 0.489362 (-5460 4035);
PAINT MONO (-5460 4035);
FORCEPROP 0 LASTPIN (-5450 4875) $PN CE67
J 2
(-5460 4885);
DISPLAY 0.489362 (-5460 4885);
PAINT MONO (-5460 4885);
FORCEPROP 0 LASTPIN (-5450 4775) $PN CL67
J 2
(-5460 4785);
DISPLAY 0.489362 (-5460 4785);
PAINT MONO (-5460 4785);
FORCEPROP 0 LASTPIN (-5450 4675) $PN CU67
J 2
(-5460 4685);
DISPLAY 0.489362 (-5460 4685);
PAINT MONO (-5460 4685);
FORCEPROP 0 LASTPIN (-5450 4575) $PN DC67
J 2
(-5460 4585);
DISPLAY 0.489362 (-5460 4585);
PAINT MONO (-5460 4585);
FORCEPROP 0 LASTPIN (-5450 4475) $PN BW66
J 2
(-5460 4485);
DISPLAY 0.489362 (-5460 4485);
PAINT MONO (-5460 4485);
FORCEPROP 0 LASTPIN (-5450 4375) $PN CE66
J 2
(-5460 4385);
DISPLAY 0.489362 (-5460 4385);
PAINT MONO (-5460 4385);
FORCEPROP 0 LASTPIN (-5450 4275) $PN CL66
J 2
(-5460 4285);
DISPLAY 0.489362 (-5460 4285);
PAINT MONO (-5460 4285);
FORCEPROP 0 LASTPIN (-5450 4175) $PN CU66
J 2
(-5460 4185);
DISPLAY 0.489362 (-5460 4185);
PAINT MONO (-5460 4185);
FORCEPROP 0 LASTPIN (-5450 4075) $PN DC66
J 2
(-5460 4085);
DISPLAY 0.489362 (-5460 4085);
PAINT MONO (-5460 4085);
FORCEPROP 0 LASTPIN (-5450 3975) $PN BW67
J 2
(-5460 3985);
DISPLAY 0.489362 (-5460 3985);
PAINT MONO (-5460 3985);
FORCEPROP 0 LASTPIN (-5450 2225) $PN BL67
J 2
(-5460 2235);
DISPLAY 0.489362 (-5460 2235);
PAINT MONO (-5460 2235);
FORCEPROP 0 LASTPIN (-5450 1175) $PN BF65
J 2
(-5460 1185);
DISPLAY 0.489362 (-5460 1185);
PAINT MONO (-5460 1185);
FORCEPROP 2 LAST PART_TYPE SMLF
J 0
(-5300 6350);
DISPLAY 1.021277 (-5300 6350);
FORCEPROP 1 LAST MATERIAL IO
J 0
(-5295 6157);
DISPLAY 0.489362 (-5295 6157);
PAINT SKYBLUE (-5295 6157);
FORCEPROP 2 LAST VALUE SOCKET6096_13568-001
J 0
(-5300 6250);
DISPLAY 0.489362 (-5300 6250);
PAINT SKYBLUE (-5300 6250);
FORCEPROP 2 LAST CDS_LIB pure_quanta
J 0
(-4650 3600);
DISPLAY INVISIBLE (-4650 3600);
FORCEPROP 1 LAST CDS_LMAN_SYM_OUTLINE -650,2525,650,-2525
J 0
(-4650 3600);
DISPLAY 0.468085 (-4650 3600);
PAINT GREEN (-4650 3600);
DISPLAY INVISIBLE (-4650 3600);
FORCEPROP 1 LAST NEEDS_NO_SIZE TRUE
J 0
(-4650 3600);
DISPLAY 0.723404 (-4650 3600);
PAINT GREEN (-4650 3600);
DISPLAY INVISIBLE (-4650 3600);
FORCEPROP 1 LAST PATH I159
J 0
(-4650 3600);
DISPLAY 0.723404 (-4650 3600);
PAINT GREEN (-4650 3600);
DISPLAY INVISIBLE (-4650 3600);
FORCEPROP 1 LAST PART_NUMBER DGA^6000030
J 0
(-5295 6284);
DISPLAY 0.489362 (-5295 6284);
PAINT SKYBLUE (-5295 6284);
DISPLAY INVISIBLE (-5295 6284);
FORCEADD OFFPAGE..3
(-2650 6000);
FORCEPROP 2 LAST $XR0 91 
J 0
(-2436 6000);
DISPLAY 0.638298 (-2436 6000);
PAINT MONO (-2436 6000);
FORCEPROP 2 LAST CDS_LIB mstr_standard
J 0
(-2650 6000);
DISPLAY 0.723404 (-2650 6000);
PAINT MONO (-2650 6000);
DISPLAY INVISIBLE (-2650 6000);
FORCEPROP 1 LAST OFFPAGE TRUE
J 0
(-2325 5875);
DISPLAY 0.872340 (-2325 5875);
PAINT GREEN (-2325 5875);
DISPLAY INVISIBLE (-2325 5875);
FORCEPROP 1 LAST COMMENT_BODY TRUE
J 0
(-2700 5900);
DISPLAY 0.872340 (-2700 5900);
PAINT GREEN (-2700 5900);
DISPLAY INVISIBLE (-2700 5900);
FORCEPROP 2 LAST PATH I160
J 0
(-2425 6050);
DISPLAY 1.021277 (-2425 6050);
DISPLAY INVISIBLE (-2425 6050);
FORCEADD OFFPAGE..3
(-2650 4200);
FORCEPROP 2 LAST $XR0 91 
J 0
(-2436 4200);
DISPLAY 0.638298 (-2436 4200);
PAINT MONO (-2436 4200);
FORCEPROP 2 LAST CDS_LIB mstr_standard
J 0
(-2650 4200);
DISPLAY 0.723404 (-2650 4200);
PAINT MONO (-2650 4200);
DISPLAY INVISIBLE (-2650 4200);
FORCEPROP 1 LAST OFFPAGE TRUE
J 0
(-2325 4075);
DISPLAY 0.872340 (-2325 4075);
PAINT GREEN (-2325 4075);
DISPLAY INVISIBLE (-2325 4075);
FORCEPROP 1 LAST COMMENT_BODY TRUE
J 0
(-2700 4100);
DISPLAY 0.872340 (-2700 4100);
PAINT GREEN (-2700 4100);
DISPLAY INVISIBLE (-2700 4100);
FORCEPROP 2 LAST PATH I161
J 0
(-2425 4250);
DISPLAY 1.021277 (-2425 4250);
DISPLAY INVISIBLE (-2425 4250);
FORCEADD TAP..1
(-3375 5975);
FORCEPROP 3 LASTPIN (-3425 5975) SIG_NAME M_F_CPU0_SA_DQ<0>
J 0
(-3415 5985);
DISPLAY 0.659574 (-3415 5985);
PAINT MONO (-3415 5985);
DISPLAY INVISIBLE (-3415 5985);
FORCEPROP 1 LASTPIN (-3425 5975) BN 0
J 0
(-3437 5983);
DISPLAY 0.489362 (-3437 5983);
PAINT GREEN (-3437 5983);
FORCEPROP 2 LAST CDS_LIB mstr_standard
J 0
(-3375 5975);
DISPLAY 0.723404 (-3375 5975);
PAINT MONO (-3375 5975);
DISPLAY INVISIBLE (-3375 5975);
FORCEPROP 1 LAST BODY_TYPE PLUMBING
J 0
(-3375 6025);
DISPLAY 0.872340 (-3375 6025);
PAINT GREEN (-3375 6025);
DISPLAY INVISIBLE (-3375 6025);
FORCEPROP 1 LAST HDL_TAP TRUE
J 0
(-3050 5850);
DISPLAY 0.872340 (-3050 5850);
DISPLAY INVISIBLE (-3050 5850);
FORCEPROP 1 LAST PATH I162
J 0
(-3377 5975);
DISPLAY 0.872340 (-3377 5975);
PAINT GREEN (-3377 5975);
DISPLAY INVISIBLE (-3377 5975);
FORCEADD TAP..1
(-3375 5925);
FORCEPROP 3 LASTPIN (-3425 5925) SIG_NAME M_F_CPU0_SA_DQ<1>
J 0
(-3415 5935);
DISPLAY 0.659574 (-3415 5935);
PAINT MONO (-3415 5935);
DISPLAY INVISIBLE (-3415 5935);
FORCEPROP 1 LASTPIN (-3425 5925) BN 1
J 0
(-3437 5933);
DISPLAY 0.489362 (-3437 5933);
PAINT GREEN (-3437 5933);
FORCEPROP 2 LAST CDS_LIB mstr_standard
J 0
(-3375 5925);
DISPLAY 0.723404 (-3375 5925);
PAINT MONO (-3375 5925);
DISPLAY INVISIBLE (-3375 5925);
FORCEPROP 1 LAST BODY_TYPE PLUMBING
J 0
(-3375 5975);
DISPLAY 0.872340 (-3375 5975);
PAINT GREEN (-3375 5975);
DISPLAY INVISIBLE (-3375 5975);
FORCEPROP 1 LAST HDL_TAP TRUE
J 0
(-3050 5800);
DISPLAY 0.872340 (-3050 5800);
DISPLAY INVISIBLE (-3050 5800);
FORCEPROP 1 LAST PATH I163
J 0
(-3377 5925);
DISPLAY 0.872340 (-3377 5925);
PAINT GREEN (-3377 5925);
DISPLAY INVISIBLE (-3377 5925);
FORCEADD TAP..1
(-3375 5775);
FORCEPROP 3 LASTPIN (-3425 5775) SIG_NAME M_F_CPU0_SA_DQ<4>
J 0
(-3415 5785);
DISPLAY 0.659574 (-3415 5785);
PAINT MONO (-3415 5785);
DISPLAY INVISIBLE (-3415 5785);
FORCEPROP 1 LASTPIN (-3425 5775) BN 4
J 0
(-3437 5783);
DISPLAY 0.489362 (-3437 5783);
PAINT GREEN (-3437 5783);
FORCEPROP 2 LAST CDS_LIB mstr_standard
J 0
(-3375 5775);
DISPLAY 0.723404 (-3375 5775);
PAINT MONO (-3375 5775);
DISPLAY INVISIBLE (-3375 5775);
FORCEPROP 1 LAST BODY_TYPE PLUMBING
J 0
(-3375 5825);
DISPLAY 0.872340 (-3375 5825);
PAINT GREEN (-3375 5825);
DISPLAY INVISIBLE (-3375 5825);
FORCEPROP 1 LAST HDL_TAP TRUE
J 0
(-3050 5650);
DISPLAY 0.872340 (-3050 5650);
DISPLAY INVISIBLE (-3050 5650);
FORCEPROP 1 LAST PATH I164
J 0
(-3377 5775);
DISPLAY 0.872340 (-3377 5775);
PAINT GREEN (-3377 5775);
DISPLAY INVISIBLE (-3377 5775);
FORCEADD TAP..1
(-3375 5825);
FORCEPROP 3 LASTPIN (-3425 5825) SIG_NAME M_F_CPU0_SA_DQ<3>
J 0
(-3415 5835);
DISPLAY 0.659574 (-3415 5835);
PAINT MONO (-3415 5835);
DISPLAY INVISIBLE (-3415 5835);
FORCEPROP 1 LASTPIN (-3425 5825) BN 3
J 0
(-3437 5833);
DISPLAY 0.489362 (-3437 5833);
PAINT GREEN (-3437 5833);
FORCEPROP 2 LAST CDS_LIB mstr_standard
J 0
(-3375 5825);
DISPLAY 0.723404 (-3375 5825);
PAINT MONO (-3375 5825);
DISPLAY INVISIBLE (-3375 5825);
FORCEPROP 1 LAST BODY_TYPE PLUMBING
J 0
(-3375 5875);
DISPLAY 0.872340 (-3375 5875);
PAINT GREEN (-3375 5875);
DISPLAY INVISIBLE (-3375 5875);
FORCEPROP 1 LAST HDL_TAP TRUE
J 0
(-3050 5700);
DISPLAY 0.872340 (-3050 5700);
DISPLAY INVISIBLE (-3050 5700);
FORCEPROP 1 LAST PATH I165
J 0
(-3377 5825);
DISPLAY 0.872340 (-3377 5825);
PAINT GREEN (-3377 5825);
DISPLAY INVISIBLE (-3377 5825);
FORCEADD TAP..1
(-3375 5875);
FORCEPROP 3 LASTPIN (-3425 5875) SIG_NAME M_F_CPU0_SA_DQ<2>
J 0
(-3415 5885);
DISPLAY 0.659574 (-3415 5885);
PAINT MONO (-3415 5885);
DISPLAY INVISIBLE (-3415 5885);
FORCEPROP 1 LASTPIN (-3425 5875) BN 2
J 0
(-3437 5883);
DISPLAY 0.489362 (-3437 5883);
PAINT GREEN (-3437 5883);
FORCEPROP 2 LAST CDS_LIB mstr_standard
J 0
(-3375 5875);
DISPLAY 0.723404 (-3375 5875);
PAINT MONO (-3375 5875);
DISPLAY INVISIBLE (-3375 5875);
FORCEPROP 1 LAST BODY_TYPE PLUMBING
J 0
(-3375 5925);
DISPLAY 0.872340 (-3375 5925);
PAINT GREEN (-3375 5925);
DISPLAY INVISIBLE (-3375 5925);
FORCEPROP 1 LAST HDL_TAP TRUE
J 0
(-3050 5750);
DISPLAY 0.872340 (-3050 5750);
DISPLAY INVISIBLE (-3050 5750);
FORCEPROP 1 LAST PATH I166
J 0
(-3377 5875);
DISPLAY 0.872340 (-3377 5875);
PAINT GREEN (-3377 5875);
DISPLAY INVISIBLE (-3377 5875);
FORCEADD TAP..1
(-3375 5675);
FORCEPROP 3 LASTPIN (-3425 5675) SIG_NAME M_F_CPU0_SA_DQ<6>
J 0
(-3415 5685);
DISPLAY 0.659574 (-3415 5685);
PAINT MONO (-3415 5685);
DISPLAY INVISIBLE (-3415 5685);
FORCEPROP 1 LASTPIN (-3425 5675) BN 6
J 0
(-3437 5683);
DISPLAY 0.489362 (-3437 5683);
PAINT GREEN (-3437 5683);
FORCEPROP 2 LAST CDS_LIB mstr_standard
J 0
(-3375 5675);
DISPLAY 0.723404 (-3375 5675);
PAINT MONO (-3375 5675);
DISPLAY INVISIBLE (-3375 5675);
FORCEPROP 1 LAST BODY_TYPE PLUMBING
J 0
(-3375 5725);
DISPLAY 0.872340 (-3375 5725);
PAINT GREEN (-3375 5725);
DISPLAY INVISIBLE (-3375 5725);
FORCEPROP 1 LAST HDL_TAP TRUE
J 0
(-3050 5550);
DISPLAY 0.872340 (-3050 5550);
DISPLAY INVISIBLE (-3050 5550);
FORCEPROP 1 LAST PATH I167
J 0
(-3377 5675);
DISPLAY 0.872340 (-3377 5675);
PAINT GREEN (-3377 5675);
DISPLAY INVISIBLE (-3377 5675);
FORCEADD TAP..1
(-3375 5725);
FORCEPROP 3 LASTPIN (-3425 5725) SIG_NAME M_F_CPU0_SA_DQ<5>
J 0
(-3415 5735);
DISPLAY 0.659574 (-3415 5735);
PAINT MONO (-3415 5735);
DISPLAY INVISIBLE (-3415 5735);
FORCEPROP 1 LASTPIN (-3425 5725) BN 5
J 0
(-3437 5733);
DISPLAY 0.489362 (-3437 5733);
PAINT GREEN (-3437 5733);
FORCEPROP 2 LAST CDS_LIB mstr_standard
J 0
(-3375 5725);
DISPLAY 0.723404 (-3375 5725);
PAINT MONO (-3375 5725);
DISPLAY INVISIBLE (-3375 5725);
FORCEPROP 1 LAST BODY_TYPE PLUMBING
J 0
(-3375 5775);
DISPLAY 0.872340 (-3375 5775);
PAINT GREEN (-3375 5775);
DISPLAY INVISIBLE (-3375 5775);
FORCEPROP 1 LAST HDL_TAP TRUE
J 0
(-3050 5600);
DISPLAY 0.872340 (-3050 5600);
DISPLAY INVISIBLE (-3050 5600);
FORCEPROP 1 LAST PATH I168
J 0
(-3377 5725);
DISPLAY 0.872340 (-3377 5725);
PAINT GREEN (-3377 5725);
DISPLAY INVISIBLE (-3377 5725);
FORCEADD TAP..1
(-3375 5525);
FORCEPROP 3 LASTPIN (-3425 5525) SIG_NAME M_F_CPU0_SA_DQ<8>
J 0
(-3415 5535);
DISPLAY 0.659574 (-3415 5535);
PAINT MONO (-3415 5535);
DISPLAY INVISIBLE (-3415 5535);
FORCEPROP 1 LASTPIN (-3425 5525) BN 8
J 0
(-3437 5533);
DISPLAY 0.489362 (-3437 5533);
PAINT GREEN (-3437 5533);
FORCEPROP 2 LAST CDS_LIB mstr_standard
J 0
(-3375 5525);
DISPLAY 0.723404 (-3375 5525);
PAINT MONO (-3375 5525);
DISPLAY INVISIBLE (-3375 5525);
FORCEPROP 1 LAST BODY_TYPE PLUMBING
J 0
(-3375 5575);
DISPLAY 0.872340 (-3375 5575);
PAINT GREEN (-3375 5575);
DISPLAY INVISIBLE (-3375 5575);
FORCEPROP 1 LAST HDL_TAP TRUE
J 0
(-3050 5400);
DISPLAY 0.872340 (-3050 5400);
DISPLAY INVISIBLE (-3050 5400);
FORCEPROP 1 LAST PATH I169
J 0
(-3377 5525);
DISPLAY 0.872340 (-3377 5525);
PAINT GREEN (-3377 5525);
DISPLAY INVISIBLE (-3377 5525);
FORCEADD TAP..1
(-3375 5625);
FORCEPROP 3 LASTPIN (-3425 5625) SIG_NAME M_F_CPU0_SA_DQ<7>
J 0
(-3415 5635);
DISPLAY 0.659574 (-3415 5635);
PAINT MONO (-3415 5635);
DISPLAY INVISIBLE (-3415 5635);
FORCEPROP 1 LASTPIN (-3425 5625) BN 7
J 0
(-3437 5633);
DISPLAY 0.489362 (-3437 5633);
PAINT GREEN (-3437 5633);
FORCEPROP 2 LAST CDS_LIB mstr_standard
J 0
(-3375 5625);
DISPLAY 0.723404 (-3375 5625);
PAINT MONO (-3375 5625);
DISPLAY INVISIBLE (-3375 5625);
FORCEPROP 1 LAST BODY_TYPE PLUMBING
J 0
(-3375 5675);
DISPLAY 0.872340 (-3375 5675);
PAINT GREEN (-3375 5675);
DISPLAY INVISIBLE (-3375 5675);
FORCEPROP 1 LAST HDL_TAP TRUE
J 0
(-3050 5500);
DISPLAY 0.872340 (-3050 5500);
DISPLAY INVISIBLE (-3050 5500);
FORCEPROP 1 LAST PATH I170
J 0
(-3377 5625);
DISPLAY 0.872340 (-3377 5625);
PAINT GREEN (-3377 5625);
DISPLAY INVISIBLE (-3377 5625);
FORCEADD TAP..1
(-3375 5475);
FORCEPROP 3 LASTPIN (-3425 5475) SIG_NAME M_F_CPU0_SA_DQ<9>
J 0
(-3415 5485);
DISPLAY 0.659574 (-3415 5485);
PAINT MONO (-3415 5485);
DISPLAY INVISIBLE (-3415 5485);
FORCEPROP 1 LASTPIN (-3425 5475) BN 9
J 0
(-3437 5483);
DISPLAY 0.489362 (-3437 5483);
PAINT GREEN (-3437 5483);
FORCEPROP 2 LAST CDS_LIB mstr_standard
J 0
(-3375 5475);
DISPLAY 0.723404 (-3375 5475);
PAINT MONO (-3375 5475);
DISPLAY INVISIBLE (-3375 5475);
FORCEPROP 1 LAST BODY_TYPE PLUMBING
J 0
(-3375 5525);
DISPLAY 0.872340 (-3375 5525);
PAINT GREEN (-3375 5525);
DISPLAY INVISIBLE (-3375 5525);
FORCEPROP 1 LAST HDL_TAP TRUE
J 0
(-3050 5350);
DISPLAY 0.872340 (-3050 5350);
DISPLAY INVISIBLE (-3050 5350);
FORCEPROP 1 LAST PATH I171
J 0
(-3377 5475);
DISPLAY 0.872340 (-3377 5475);
PAINT GREEN (-3377 5475);
DISPLAY INVISIBLE (-3377 5475);
FORCEADD TAP..1
(-3375 5425);
FORCEPROP 3 LASTPIN (-3425 5425) SIG_NAME M_F_CPU0_SA_DQ<10>
J 0
(-3415 5435);
DISPLAY 0.659574 (-3415 5435);
PAINT MONO (-3415 5435);
DISPLAY INVISIBLE (-3415 5435);
FORCEPROP 1 LASTPIN (-3425 5425) BN 10
J 0
(-3437 5433);
DISPLAY 0.489362 (-3437 5433);
PAINT GREEN (-3437 5433);
FORCEPROP 2 LAST CDS_LIB mstr_standard
J 0
(-3375 5425);
DISPLAY 0.723404 (-3375 5425);
PAINT MONO (-3375 5425);
DISPLAY INVISIBLE (-3375 5425);
FORCEPROP 1 LAST BODY_TYPE PLUMBING
J 0
(-3375 5475);
DISPLAY 0.872340 (-3375 5475);
PAINT GREEN (-3375 5475);
DISPLAY INVISIBLE (-3375 5475);
FORCEPROP 1 LAST HDL_TAP TRUE
J 0
(-3050 5300);
DISPLAY 0.872340 (-3050 5300);
DISPLAY INVISIBLE (-3050 5300);
FORCEPROP 1 LAST PATH I172
J 0
(-3377 5425);
DISPLAY 0.872340 (-3377 5425);
PAINT GREEN (-3377 5425);
DISPLAY INVISIBLE (-3377 5425);
FORCEADD TAP..1
(-3375 5275);
FORCEPROP 3 LASTPIN (-3425 5275) SIG_NAME M_F_CPU0_SA_DQ<13>
J 0
(-3415 5285);
DISPLAY 0.659574 (-3415 5285);
PAINT MONO (-3415 5285);
DISPLAY INVISIBLE (-3415 5285);
FORCEPROP 1 LASTPIN (-3425 5275) BN 13
J 0
(-3437 5283);
DISPLAY 0.489362 (-3437 5283);
PAINT GREEN (-3437 5283);
FORCEPROP 2 LAST CDS_LIB mstr_standard
J 0
(-3375 5275);
DISPLAY 0.723404 (-3375 5275);
PAINT MONO (-3375 5275);
DISPLAY INVISIBLE (-3375 5275);
FORCEPROP 1 LAST BODY_TYPE PLUMBING
J 0
(-3375 5325);
DISPLAY 0.872340 (-3375 5325);
PAINT GREEN (-3375 5325);
DISPLAY INVISIBLE (-3375 5325);
FORCEPROP 1 LAST HDL_TAP TRUE
J 0
(-3050 5150);
DISPLAY 0.872340 (-3050 5150);
DISPLAY INVISIBLE (-3050 5150);
FORCEPROP 1 LAST PATH I173
J 0
(-3377 5275);
DISPLAY 0.872340 (-3377 5275);
PAINT GREEN (-3377 5275);
DISPLAY INVISIBLE (-3377 5275);
FORCEADD TAP..1
(-3375 5325);
FORCEPROP 3 LASTPIN (-3425 5325) SIG_NAME M_F_CPU0_SA_DQ<12>
J 0
(-3415 5335);
DISPLAY 0.659574 (-3415 5335);
PAINT MONO (-3415 5335);
DISPLAY INVISIBLE (-3415 5335);
FORCEPROP 1 LASTPIN (-3425 5325) BN 12
J 0
(-3437 5333);
DISPLAY 0.489362 (-3437 5333);
PAINT GREEN (-3437 5333);
FORCEPROP 2 LAST CDS_LIB mstr_standard
J 0
(-3375 5325);
DISPLAY 0.723404 (-3375 5325);
PAINT MONO (-3375 5325);
DISPLAY INVISIBLE (-3375 5325);
FORCEPROP 1 LAST BODY_TYPE PLUMBING
J 0
(-3375 5375);
DISPLAY 0.872340 (-3375 5375);
PAINT GREEN (-3375 5375);
DISPLAY INVISIBLE (-3375 5375);
FORCEPROP 1 LAST HDL_TAP TRUE
J 0
(-3050 5200);
DISPLAY 0.872340 (-3050 5200);
DISPLAY INVISIBLE (-3050 5200);
FORCEPROP 1 LAST PATH I174
J 0
(-3377 5325);
DISPLAY 0.872340 (-3377 5325);
PAINT GREEN (-3377 5325);
DISPLAY INVISIBLE (-3377 5325);
FORCEADD TAP..1
(-3375 5375);
FORCEPROP 3 LASTPIN (-3425 5375) SIG_NAME M_F_CPU0_SA_DQ<11>
J 0
(-3415 5385);
DISPLAY 0.659574 (-3415 5385);
PAINT MONO (-3415 5385);
DISPLAY INVISIBLE (-3415 5385);
FORCEPROP 1 LASTPIN (-3425 5375) BN 11
J 0
(-3437 5383);
DISPLAY 0.489362 (-3437 5383);
PAINT GREEN (-3437 5383);
FORCEPROP 2 LAST CDS_LIB mstr_standard
J 0
(-3375 5375);
DISPLAY 0.723404 (-3375 5375);
PAINT MONO (-3375 5375);
DISPLAY INVISIBLE (-3375 5375);
FORCEPROP 1 LAST BODY_TYPE PLUMBING
J 0
(-3375 5425);
DISPLAY 0.872340 (-3375 5425);
PAINT GREEN (-3375 5425);
DISPLAY INVISIBLE (-3375 5425);
FORCEPROP 1 LAST HDL_TAP TRUE
J 0
(-3050 5250);
DISPLAY 0.872340 (-3050 5250);
DISPLAY INVISIBLE (-3050 5250);
FORCEPROP 1 LAST PATH I175
J 0
(-3377 5375);
DISPLAY 0.872340 (-3377 5375);
PAINT GREEN (-3377 5375);
DISPLAY INVISIBLE (-3377 5375);
FORCEADD TAP..1
(-3375 5175);
FORCEPROP 3 LASTPIN (-3425 5175) SIG_NAME M_F_CPU0_SA_DQ<15>
J 0
(-3415 5185);
DISPLAY 0.659574 (-3415 5185);
PAINT MONO (-3415 5185);
DISPLAY INVISIBLE (-3415 5185);
FORCEPROP 1 LASTPIN (-3425 5175) BN 15
J 0
(-3437 5183);
DISPLAY 0.489362 (-3437 5183);
PAINT GREEN (-3437 5183);
FORCEPROP 2 LAST CDS_LIB mstr_standard
J 0
(-3375 5175);
DISPLAY 0.723404 (-3375 5175);
PAINT MONO (-3375 5175);
DISPLAY INVISIBLE (-3375 5175);
FORCEPROP 1 LAST BODY_TYPE PLUMBING
J 0
(-3375 5225);
DISPLAY 0.872340 (-3375 5225);
PAINT GREEN (-3375 5225);
DISPLAY INVISIBLE (-3375 5225);
FORCEPROP 1 LAST HDL_TAP TRUE
J 0
(-3050 5050);
DISPLAY 0.872340 (-3050 5050);
DISPLAY INVISIBLE (-3050 5050);
FORCEPROP 1 LAST PATH I176
J 0
(-3377 5175);
DISPLAY 0.872340 (-3377 5175);
PAINT GREEN (-3377 5175);
DISPLAY INVISIBLE (-3377 5175);
FORCEADD TAP..1
(-3375 5225);
FORCEPROP 3 LASTPIN (-3425 5225) SIG_NAME M_F_CPU0_SA_DQ<14>
J 0
(-3415 5235);
DISPLAY 0.659574 (-3415 5235);
PAINT MONO (-3415 5235);
DISPLAY INVISIBLE (-3415 5235);
FORCEPROP 1 LASTPIN (-3425 5225) BN 14
J 0
(-3437 5233);
DISPLAY 0.489362 (-3437 5233);
PAINT GREEN (-3437 5233);
FORCEPROP 2 LAST CDS_LIB mstr_standard
J 0
(-3375 5225);
DISPLAY 0.723404 (-3375 5225);
PAINT MONO (-3375 5225);
DISPLAY INVISIBLE (-3375 5225);
FORCEPROP 1 LAST BODY_TYPE PLUMBING
J 0
(-3375 5275);
DISPLAY 0.872340 (-3375 5275);
PAINT GREEN (-3375 5275);
DISPLAY INVISIBLE (-3375 5275);
FORCEPROP 1 LAST HDL_TAP TRUE
J 0
(-3050 5100);
DISPLAY 0.872340 (-3050 5100);
DISPLAY INVISIBLE (-3050 5100);
FORCEPROP 1 LAST PATH I177
J 0
(-3377 5225);
DISPLAY 0.872340 (-3377 5225);
PAINT GREEN (-3377 5225);
DISPLAY INVISIBLE (-3377 5225);
FORCEADD TAP..1
(-3375 5025);
FORCEPROP 3 LASTPIN (-3425 5025) SIG_NAME M_F_CPU0_SA_DQ<17>
J 0
(-3415 5035);
DISPLAY 0.659574 (-3415 5035);
PAINT MONO (-3415 5035);
DISPLAY INVISIBLE (-3415 5035);
FORCEPROP 1 LASTPIN (-3425 5025) BN 17
J 0
(-3437 5033);
DISPLAY 0.489362 (-3437 5033);
PAINT GREEN (-3437 5033);
FORCEPROP 2 LAST CDS_LIB mstr_standard
J 0
(-3375 5025);
DISPLAY 0.723404 (-3375 5025);
PAINT MONO (-3375 5025);
DISPLAY INVISIBLE (-3375 5025);
FORCEPROP 1 LAST BODY_TYPE PLUMBING
J 0
(-3375 5075);
DISPLAY 0.872340 (-3375 5075);
PAINT GREEN (-3375 5075);
DISPLAY INVISIBLE (-3375 5075);
FORCEPROP 1 LAST HDL_TAP TRUE
J 0
(-3050 4900);
DISPLAY 0.872340 (-3050 4900);
DISPLAY INVISIBLE (-3050 4900);
FORCEPROP 1 LAST PATH I178
J 0
(-3377 5025);
DISPLAY 0.872340 (-3377 5025);
PAINT GREEN (-3377 5025);
DISPLAY INVISIBLE (-3377 5025);
FORCEADD TAP..1
(-3375 5075);
FORCEPROP 3 LASTPIN (-3425 5075) SIG_NAME M_F_CPU0_SA_DQ<16>
J 0
(-3415 5085);
DISPLAY 0.659574 (-3415 5085);
PAINT MONO (-3415 5085);
DISPLAY INVISIBLE (-3415 5085);
FORCEPROP 1 LASTPIN (-3425 5075) BN 16
J 0
(-3437 5083);
DISPLAY 0.489362 (-3437 5083);
PAINT GREEN (-3437 5083);
FORCEPROP 2 LAST CDS_LIB mstr_standard
J 0
(-3375 5075);
DISPLAY 0.723404 (-3375 5075);
PAINT MONO (-3375 5075);
DISPLAY INVISIBLE (-3375 5075);
FORCEPROP 1 LAST BODY_TYPE PLUMBING
J 0
(-3375 5125);
DISPLAY 0.872340 (-3375 5125);
PAINT GREEN (-3375 5125);
DISPLAY INVISIBLE (-3375 5125);
FORCEPROP 1 LAST HDL_TAP TRUE
J 0
(-3050 4950);
DISPLAY 0.872340 (-3050 4950);
DISPLAY INVISIBLE (-3050 4950);
FORCEPROP 1 LAST PATH I179
J 0
(-3377 5075);
DISPLAY 0.872340 (-3377 5075);
PAINT GREEN (-3377 5075);
DISPLAY INVISIBLE (-3377 5075);
FORCEADD TAP..1
(-3375 4875);
FORCEPROP 3 LASTPIN (-3425 4875) SIG_NAME M_F_CPU0_SA_DQ<20>
J 0
(-3415 4885);
DISPLAY 0.659574 (-3415 4885);
PAINT MONO (-3415 4885);
DISPLAY INVISIBLE (-3415 4885);
FORCEPROP 1 LASTPIN (-3425 4875) BN 20
J 0
(-3437 4883);
DISPLAY 0.489362 (-3437 4883);
PAINT GREEN (-3437 4883);
FORCEPROP 2 LAST CDS_LIB mstr_standard
J 0
(-3375 4875);
DISPLAY 0.723404 (-3375 4875);
PAINT MONO (-3375 4875);
DISPLAY INVISIBLE (-3375 4875);
FORCEPROP 1 LAST BODY_TYPE PLUMBING
J 0
(-3375 4925);
DISPLAY 0.872340 (-3375 4925);
PAINT GREEN (-3375 4925);
DISPLAY INVISIBLE (-3375 4925);
FORCEPROP 1 LAST HDL_TAP TRUE
J 0
(-3050 4750);
DISPLAY 0.872340 (-3050 4750);
DISPLAY INVISIBLE (-3050 4750);
FORCEPROP 1 LAST PATH I180
J 0
(-3377 4875);
DISPLAY 0.872340 (-3377 4875);
PAINT GREEN (-3377 4875);
DISPLAY INVISIBLE (-3377 4875);
FORCEADD TAP..1
(-3375 4925);
FORCEPROP 3 LASTPIN (-3425 4925) SIG_NAME M_F_CPU0_SA_DQ<19>
J 0
(-3415 4935);
DISPLAY 0.659574 (-3415 4935);
PAINT MONO (-3415 4935);
DISPLAY INVISIBLE (-3415 4935);
FORCEPROP 1 LASTPIN (-3425 4925) BN 19
J 0
(-3437 4933);
DISPLAY 0.489362 (-3437 4933);
PAINT GREEN (-3437 4933);
FORCEPROP 2 LAST CDS_LIB mstr_standard
J 0
(-3375 4925);
DISPLAY 0.723404 (-3375 4925);
PAINT MONO (-3375 4925);
DISPLAY INVISIBLE (-3375 4925);
FORCEPROP 1 LAST BODY_TYPE PLUMBING
J 0
(-3375 4975);
DISPLAY 0.872340 (-3375 4975);
PAINT GREEN (-3375 4975);
DISPLAY INVISIBLE (-3375 4975);
FORCEPROP 1 LAST HDL_TAP TRUE
J 0
(-3050 4800);
DISPLAY 0.872340 (-3050 4800);
DISPLAY INVISIBLE (-3050 4800);
FORCEPROP 1 LAST PATH I181
J 0
(-3377 4925);
DISPLAY 0.872340 (-3377 4925);
PAINT GREEN (-3377 4925);
DISPLAY INVISIBLE (-3377 4925);
FORCEADD TAP..1
(-3375 4975);
FORCEPROP 3 LASTPIN (-3425 4975) SIG_NAME M_F_CPU0_SA_DQ<18>
J 0
(-3415 4985);
DISPLAY 0.659574 (-3415 4985);
PAINT MONO (-3415 4985);
DISPLAY INVISIBLE (-3415 4985);
FORCEPROP 1 LASTPIN (-3425 4975) BN 18
J 0
(-3437 4983);
DISPLAY 0.489362 (-3437 4983);
PAINT GREEN (-3437 4983);
FORCEPROP 2 LAST CDS_LIB mstr_standard
J 0
(-3375 4975);
DISPLAY 0.723404 (-3375 4975);
PAINT MONO (-3375 4975);
DISPLAY INVISIBLE (-3375 4975);
FORCEPROP 1 LAST BODY_TYPE PLUMBING
J 0
(-3375 5025);
DISPLAY 0.872340 (-3375 5025);
PAINT GREEN (-3375 5025);
DISPLAY INVISIBLE (-3375 5025);
FORCEPROP 1 LAST HDL_TAP TRUE
J 0
(-3050 4850);
DISPLAY 0.872340 (-3050 4850);
DISPLAY INVISIBLE (-3050 4850);
FORCEPROP 1 LAST PATH I182
J 0
(-3377 4975);
DISPLAY 0.872340 (-3377 4975);
PAINT GREEN (-3377 4975);
DISPLAY INVISIBLE (-3377 4975);
FORCEADD TAP..1
(-3375 4775);
FORCEPROP 3 LASTPIN (-3425 4775) SIG_NAME M_F_CPU0_SA_DQ<22>
J 0
(-3415 4785);
DISPLAY 0.659574 (-3415 4785);
PAINT MONO (-3415 4785);
DISPLAY INVISIBLE (-3415 4785);
FORCEPROP 1 LASTPIN (-3425 4775) BN 22
J 0
(-3437 4783);
DISPLAY 0.489362 (-3437 4783);
PAINT GREEN (-3437 4783);
FORCEPROP 2 LAST CDS_LIB mstr_standard
J 0
(-3375 4775);
DISPLAY 0.723404 (-3375 4775);
PAINT MONO (-3375 4775);
DISPLAY INVISIBLE (-3375 4775);
FORCEPROP 1 LAST BODY_TYPE PLUMBING
J 0
(-3375 4825);
DISPLAY 0.872340 (-3375 4825);
PAINT GREEN (-3375 4825);
DISPLAY INVISIBLE (-3375 4825);
FORCEPROP 1 LAST HDL_TAP TRUE
J 0
(-3050 4650);
DISPLAY 0.872340 (-3050 4650);
DISPLAY INVISIBLE (-3050 4650);
FORCEPROP 1 LAST PATH I183
J 0
(-3377 4775);
DISPLAY 0.872340 (-3377 4775);
PAINT GREEN (-3377 4775);
DISPLAY INVISIBLE (-3377 4775);
FORCEADD TAP..1
(-3375 4825);
FORCEPROP 3 LASTPIN (-3425 4825) SIG_NAME M_F_CPU0_SA_DQ<21>
J 0
(-3415 4835);
DISPLAY 0.659574 (-3415 4835);
PAINT MONO (-3415 4835);
DISPLAY INVISIBLE (-3415 4835);
FORCEPROP 1 LASTPIN (-3425 4825) BN 21
J 0
(-3437 4833);
DISPLAY 0.489362 (-3437 4833);
PAINT GREEN (-3437 4833);
FORCEPROP 2 LAST CDS_LIB mstr_standard
J 0
(-3375 4825);
DISPLAY 0.723404 (-3375 4825);
PAINT MONO (-3375 4825);
DISPLAY INVISIBLE (-3375 4825);
FORCEPROP 1 LAST BODY_TYPE PLUMBING
J 0
(-3375 4875);
DISPLAY 0.872340 (-3375 4875);
PAINT GREEN (-3375 4875);
DISPLAY INVISIBLE (-3375 4875);
FORCEPROP 1 LAST HDL_TAP TRUE
J 0
(-3050 4700);
DISPLAY 0.872340 (-3050 4700);
DISPLAY INVISIBLE (-3050 4700);
FORCEPROP 1 LAST PATH I184
J 0
(-3377 4825);
DISPLAY 0.872340 (-3377 4825);
PAINT GREEN (-3377 4825);
DISPLAY INVISIBLE (-3377 4825);
FORCEADD TAP..1
(-3375 4725);
FORCEPROP 3 LASTPIN (-3425 4725) SIG_NAME M_F_CPU0_SA_DQ<23>
J 0
(-3415 4735);
DISPLAY 0.659574 (-3415 4735);
PAINT MONO (-3415 4735);
DISPLAY INVISIBLE (-3415 4735);
FORCEPROP 1 LASTPIN (-3425 4725) BN 23
J 0
(-3437 4733);
DISPLAY 0.489362 (-3437 4733);
PAINT GREEN (-3437 4733);
FORCEPROP 2 LAST CDS_LIB mstr_standard
J 0
(-3375 4725);
DISPLAY 0.723404 (-3375 4725);
PAINT MONO (-3375 4725);
DISPLAY INVISIBLE (-3375 4725);
FORCEPROP 1 LAST BODY_TYPE PLUMBING
J 0
(-3375 4775);
DISPLAY 0.872340 (-3375 4775);
PAINT GREEN (-3375 4775);
DISPLAY INVISIBLE (-3375 4775);
FORCEPROP 1 LAST HDL_TAP TRUE
J 0
(-3050 4600);
DISPLAY 0.872340 (-3050 4600);
DISPLAY INVISIBLE (-3050 4600);
FORCEPROP 1 LAST PATH I185
J 0
(-3377 4725);
DISPLAY 0.872340 (-3377 4725);
PAINT GREEN (-3377 4725);
DISPLAY INVISIBLE (-3377 4725);
FORCEADD TAP..1
(-3375 4625);
FORCEPROP 3 LASTPIN (-3425 4625) SIG_NAME M_F_CPU0_SA_DQ<24>
J 0
(-3415 4635);
DISPLAY 0.659574 (-3415 4635);
PAINT MONO (-3415 4635);
DISPLAY INVISIBLE (-3415 4635);
FORCEPROP 1 LASTPIN (-3425 4625) BN 24
J 0
(-3437 4633);
DISPLAY 0.489362 (-3437 4633);
PAINT GREEN (-3437 4633);
FORCEPROP 2 LAST CDS_LIB mstr_standard
J 0
(-3375 4625);
DISPLAY 0.723404 (-3375 4625);
PAINT MONO (-3375 4625);
DISPLAY INVISIBLE (-3375 4625);
FORCEPROP 1 LAST BODY_TYPE PLUMBING
J 0
(-3375 4675);
DISPLAY 0.872340 (-3375 4675);
PAINT GREEN (-3375 4675);
DISPLAY INVISIBLE (-3375 4675);
FORCEPROP 1 LAST HDL_TAP TRUE
J 0
(-3050 4500);
DISPLAY 0.872340 (-3050 4500);
DISPLAY INVISIBLE (-3050 4500);
FORCEPROP 1 LAST PATH I186
J 0
(-3377 4625);
DISPLAY 0.872340 (-3377 4625);
PAINT GREEN (-3377 4625);
DISPLAY INVISIBLE (-3377 4625);
FORCEADD TAP..1
(-3375 4575);
FORCEPROP 3 LASTPIN (-3425 4575) SIG_NAME M_F_CPU0_SA_DQ<25>
J 0
(-3415 4585);
DISPLAY 0.659574 (-3415 4585);
PAINT MONO (-3415 4585);
DISPLAY INVISIBLE (-3415 4585);
FORCEPROP 1 LASTPIN (-3425 4575) BN 25
J 0
(-3437 4583);
DISPLAY 0.489362 (-3437 4583);
PAINT GREEN (-3437 4583);
FORCEPROP 2 LAST CDS_LIB mstr_standard
J 0
(-3375 4575);
DISPLAY 0.723404 (-3375 4575);
PAINT MONO (-3375 4575);
DISPLAY INVISIBLE (-3375 4575);
FORCEPROP 1 LAST BODY_TYPE PLUMBING
J 0
(-3375 4625);
DISPLAY 0.872340 (-3375 4625);
PAINT GREEN (-3375 4625);
DISPLAY INVISIBLE (-3375 4625);
FORCEPROP 1 LAST HDL_TAP TRUE
J 0
(-3050 4450);
DISPLAY 0.872340 (-3050 4450);
DISPLAY INVISIBLE (-3050 4450);
FORCEPROP 1 LAST PATH I187
J 0
(-3377 4575);
DISPLAY 0.872340 (-3377 4575);
PAINT GREEN (-3377 4575);
DISPLAY INVISIBLE (-3377 4575);
FORCEADD TAP..1
(-3375 4525);
FORCEPROP 3 LASTPIN (-3425 4525) SIG_NAME M_F_CPU0_SA_DQ<26>
J 0
(-3415 4535);
DISPLAY 0.659574 (-3415 4535);
PAINT MONO (-3415 4535);
DISPLAY INVISIBLE (-3415 4535);
FORCEPROP 1 LASTPIN (-3425 4525) BN 26
J 0
(-3437 4533);
DISPLAY 0.489362 (-3437 4533);
PAINT GREEN (-3437 4533);
FORCEPROP 2 LAST CDS_LIB mstr_standard
J 0
(-3375 4525);
DISPLAY 0.723404 (-3375 4525);
PAINT MONO (-3375 4525);
DISPLAY INVISIBLE (-3375 4525);
FORCEPROP 1 LAST BODY_TYPE PLUMBING
J 0
(-3375 4575);
DISPLAY 0.872340 (-3375 4575);
PAINT GREEN (-3375 4575);
DISPLAY INVISIBLE (-3375 4575);
FORCEPROP 1 LAST HDL_TAP TRUE
J 0
(-3050 4400);
DISPLAY 0.872340 (-3050 4400);
DISPLAY INVISIBLE (-3050 4400);
FORCEPROP 1 LAST PATH I188
J 0
(-3377 4525);
DISPLAY 0.872340 (-3377 4525);
PAINT GREEN (-3377 4525);
DISPLAY INVISIBLE (-3377 4525);
FORCEADD TAP..1
(-3375 4375);
FORCEPROP 3 LASTPIN (-3425 4375) SIG_NAME M_F_CPU0_SA_DQ<29>
J 0
(-3415 4385);
DISPLAY 0.659574 (-3415 4385);
PAINT MONO (-3415 4385);
DISPLAY INVISIBLE (-3415 4385);
FORCEPROP 1 LASTPIN (-3425 4375) BN 29
J 0
(-3437 4383);
DISPLAY 0.489362 (-3437 4383);
PAINT GREEN (-3437 4383);
FORCEPROP 2 LAST CDS_LIB mstr_standard
J 0
(-3375 4375);
DISPLAY 0.723404 (-3375 4375);
PAINT MONO (-3375 4375);
DISPLAY INVISIBLE (-3375 4375);
FORCEPROP 1 LAST BODY_TYPE PLUMBING
J 0
(-3375 4425);
DISPLAY 0.872340 (-3375 4425);
PAINT GREEN (-3375 4425);
DISPLAY INVISIBLE (-3375 4425);
FORCEPROP 1 LAST HDL_TAP TRUE
J 0
(-3050 4250);
DISPLAY 0.872340 (-3050 4250);
DISPLAY INVISIBLE (-3050 4250);
FORCEPROP 1 LAST PATH I189
J 0
(-3377 4375);
DISPLAY 0.872340 (-3377 4375);
PAINT GREEN (-3377 4375);
DISPLAY INVISIBLE (-3377 4375);
FORCEADD TAP..1
(-3375 4425);
FORCEPROP 3 LASTPIN (-3425 4425) SIG_NAME M_F_CPU0_SA_DQ<28>
J 0
(-3415 4435);
DISPLAY 0.659574 (-3415 4435);
PAINT MONO (-3415 4435);
DISPLAY INVISIBLE (-3415 4435);
FORCEPROP 1 LASTPIN (-3425 4425) BN 28
J 0
(-3437 4433);
DISPLAY 0.489362 (-3437 4433);
PAINT GREEN (-3437 4433);
FORCEPROP 2 LAST CDS_LIB mstr_standard
J 0
(-3375 4425);
DISPLAY 0.723404 (-3375 4425);
PAINT MONO (-3375 4425);
DISPLAY INVISIBLE (-3375 4425);
FORCEPROP 1 LAST BODY_TYPE PLUMBING
J 0
(-3375 4475);
DISPLAY 0.872340 (-3375 4475);
PAINT GREEN (-3375 4475);
DISPLAY INVISIBLE (-3375 4475);
FORCEPROP 1 LAST HDL_TAP TRUE
J 0
(-3050 4300);
DISPLAY 0.872340 (-3050 4300);
DISPLAY INVISIBLE (-3050 4300);
FORCEPROP 1 LAST PATH I190
J 0
(-3377 4425);
DISPLAY 0.872340 (-3377 4425);
PAINT GREEN (-3377 4425);
DISPLAY INVISIBLE (-3377 4425);
FORCEADD TAP..1
(-3375 4475);
FORCEPROP 3 LASTPIN (-3425 4475) SIG_NAME M_F_CPU0_SA_DQ<27>
J 0
(-3415 4485);
DISPLAY 0.659574 (-3415 4485);
PAINT MONO (-3415 4485);
DISPLAY INVISIBLE (-3415 4485);
FORCEPROP 1 LASTPIN (-3425 4475) BN 27
J 0
(-3437 4483);
DISPLAY 0.489362 (-3437 4483);
PAINT GREEN (-3437 4483);
FORCEPROP 2 LAST CDS_LIB mstr_standard
J 0
(-3375 4475);
DISPLAY 0.723404 (-3375 4475);
PAINT MONO (-3375 4475);
DISPLAY INVISIBLE (-3375 4475);
FORCEPROP 1 LAST BODY_TYPE PLUMBING
J 0
(-3375 4525);
DISPLAY 0.872340 (-3375 4525);
PAINT GREEN (-3375 4525);
DISPLAY INVISIBLE (-3375 4525);
FORCEPROP 1 LAST HDL_TAP TRUE
J 0
(-3050 4350);
DISPLAY 0.872340 (-3050 4350);
DISPLAY INVISIBLE (-3050 4350);
FORCEPROP 1 LAST PATH I191
J 0
(-3377 4475);
DISPLAY 0.872340 (-3377 4475);
PAINT GREEN (-3377 4475);
DISPLAY INVISIBLE (-3377 4475);
FORCEADD TAP..1
(-3375 4275);
FORCEPROP 3 LASTPIN (-3425 4275) SIG_NAME M_F_CPU0_SA_DQ<31>
J 0
(-3415 4285);
DISPLAY 0.659574 (-3415 4285);
PAINT MONO (-3415 4285);
DISPLAY INVISIBLE (-3415 4285);
FORCEPROP 1 LASTPIN (-3425 4275) BN 31
J 0
(-3437 4283);
DISPLAY 0.489362 (-3437 4283);
PAINT GREEN (-3437 4283);
FORCEPROP 2 LAST CDS_LIB mstr_standard
J 0
(-3375 4275);
DISPLAY 0.723404 (-3375 4275);
PAINT MONO (-3375 4275);
DISPLAY INVISIBLE (-3375 4275);
FORCEPROP 1 LAST BODY_TYPE PLUMBING
J 0
(-3375 4325);
DISPLAY 0.872340 (-3375 4325);
PAINT GREEN (-3375 4325);
DISPLAY INVISIBLE (-3375 4325);
FORCEPROP 1 LAST HDL_TAP TRUE
J 0
(-3050 4150);
DISPLAY 0.872340 (-3050 4150);
DISPLAY INVISIBLE (-3050 4150);
FORCEPROP 1 LAST PATH I192
J 0
(-3377 4275);
DISPLAY 0.872340 (-3377 4275);
PAINT GREEN (-3377 4275);
DISPLAY INVISIBLE (-3377 4275);
FORCEADD TAP..1
(-3375 4325);
FORCEPROP 3 LASTPIN (-3425 4325) SIG_NAME M_F_CPU0_SA_DQ<30>
J 0
(-3415 4335);
DISPLAY 0.659574 (-3415 4335);
PAINT MONO (-3415 4335);
DISPLAY INVISIBLE (-3415 4335);
FORCEPROP 1 LASTPIN (-3425 4325) BN 30
J 0
(-3437 4333);
DISPLAY 0.489362 (-3437 4333);
PAINT GREEN (-3437 4333);
FORCEPROP 2 LAST CDS_LIB mstr_standard
J 0
(-3375 4325);
DISPLAY 0.723404 (-3375 4325);
PAINT MONO (-3375 4325);
DISPLAY INVISIBLE (-3375 4325);
FORCEPROP 1 LAST BODY_TYPE PLUMBING
J 0
(-3375 4375);
DISPLAY 0.872340 (-3375 4375);
PAINT GREEN (-3375 4375);
DISPLAY INVISIBLE (-3375 4375);
FORCEPROP 1 LAST HDL_TAP TRUE
J 0
(-3050 4200);
DISPLAY 0.872340 (-3050 4200);
DISPLAY INVISIBLE (-3050 4200);
FORCEPROP 1 LAST PATH I193
J 0
(-3377 4325);
DISPLAY 0.872340 (-3377 4325);
PAINT GREEN (-3377 4325);
DISPLAY INVISIBLE (-3377 4325);
FORCEADD TAP..1
(-3375 4125);
FORCEPROP 3 LASTPIN (-3425 4125) SIG_NAME M_F_CPU0_SB_DQ<1>
J 0
(-3415 4135);
DISPLAY 0.659574 (-3415 4135);
PAINT MONO (-3415 4135);
DISPLAY INVISIBLE (-3415 4135);
FORCEPROP 1 LASTPIN (-3425 4125) BN 1
J 0
(-3437 4133);
DISPLAY 0.489362 (-3437 4133);
PAINT GREEN (-3437 4133);
FORCEPROP 2 LAST CDS_LIB mstr_standard
J 0
(-3375 4125);
DISPLAY 0.723404 (-3375 4125);
PAINT MONO (-3375 4125);
DISPLAY INVISIBLE (-3375 4125);
FORCEPROP 1 LAST BODY_TYPE PLUMBING
J 0
(-3375 4175);
DISPLAY 0.872340 (-3375 4175);
PAINT GREEN (-3375 4175);
DISPLAY INVISIBLE (-3375 4175);
FORCEPROP 1 LAST HDL_TAP TRUE
J 0
(-3050 4000);
DISPLAY 0.872340 (-3050 4000);
DISPLAY INVISIBLE (-3050 4000);
FORCEPROP 1 LAST PATH I194
J 0
(-3377 4125);
DISPLAY 0.872340 (-3377 4125);
PAINT GREEN (-3377 4125);
DISPLAY INVISIBLE (-3377 4125);
FORCEADD TAP..1
(-3375 4175);
FORCEPROP 3 LASTPIN (-3425 4175) SIG_NAME M_F_CPU0_SB_DQ<0>
J 0
(-3415 4185);
DISPLAY 0.659574 (-3415 4185);
PAINT MONO (-3415 4185);
DISPLAY INVISIBLE (-3415 4185);
FORCEPROP 1 LASTPIN (-3425 4175) BN 0
J 0
(-3437 4183);
DISPLAY 0.489362 (-3437 4183);
PAINT GREEN (-3437 4183);
FORCEPROP 2 LAST CDS_LIB mstr_standard
J 0
(-3375 4175);
DISPLAY 0.723404 (-3375 4175);
PAINT MONO (-3375 4175);
DISPLAY INVISIBLE (-3375 4175);
FORCEPROP 1 LAST BODY_TYPE PLUMBING
J 0
(-3375 4225);
DISPLAY 0.872340 (-3375 4225);
PAINT GREEN (-3375 4225);
DISPLAY INVISIBLE (-3375 4225);
FORCEPROP 1 LAST HDL_TAP TRUE
J 0
(-3050 4050);
DISPLAY 0.872340 (-3050 4050);
DISPLAY INVISIBLE (-3050 4050);
FORCEPROP 1 LAST PATH I195
J 0
(-3377 4175);
DISPLAY 0.872340 (-3377 4175);
PAINT GREEN (-3377 4175);
DISPLAY INVISIBLE (-3377 4175);
FORCEADD OFFPAGE..6
R 2
(-2775 2425);
FORCEPROP 2 LAST $XR0 91 
J 0
(-2561 2425);
DISPLAY 0.638298 (-2561 2425);
PAINT MONO (-2561 2425);
FORCEPROP 2 LAST CDS_LIB mstr_standard
J 2
(-2775 2425);
DISPLAY 0.723404 (-2775 2425);
PAINT MONO (-2775 2425);
DISPLAY INVISIBLE (-2775 2425);
FORCEPROP 1 LAST OFFPAGE TRUE
J 2
(-3100 2300);
DISPLAY 0.872340 (-3100 2300);
PAINT GREEN (-3100 2300);
DISPLAY INVISIBLE (-3100 2300);
FORCEPROP 1 LAST COMMENT_BODY TRUE
J 2
(-2875 2350);
DISPLAY 0.872340 (-2875 2350);
PAINT GREEN (-2875 2350);
DISPLAY INVISIBLE (-2875 2350);
FORCEPROP 2 LAST PATH I196
J 0
(-2550 2475);
DISPLAY 1.021277 (-2550 2475);
DISPLAY INVISIBLE (-2550 2475);
FORCEADD TAP..1
(-3375 3975);
FORCEPROP 3 LASTPIN (-3425 3975) SIG_NAME M_F_CPU0_SB_DQ<4>
J 0
(-3415 3985);
DISPLAY 0.659574 (-3415 3985);
PAINT MONO (-3415 3985);
DISPLAY INVISIBLE (-3415 3985);
FORCEPROP 1 LASTPIN (-3425 3975) BN 4
J 0
(-3437 3983);
DISPLAY 0.489362 (-3437 3983);
PAINT GREEN (-3437 3983);
FORCEPROP 2 LAST CDS_LIB mstr_standard
J 0
(-3375 3975);
DISPLAY 0.723404 (-3375 3975);
PAINT MONO (-3375 3975);
DISPLAY INVISIBLE (-3375 3975);
FORCEPROP 1 LAST BODY_TYPE PLUMBING
J 0
(-3375 4025);
DISPLAY 0.872340 (-3375 4025);
PAINT GREEN (-3375 4025);
DISPLAY INVISIBLE (-3375 4025);
FORCEPROP 1 LAST HDL_TAP TRUE
J 0
(-3050 3850);
DISPLAY 0.872340 (-3050 3850);
DISPLAY INVISIBLE (-3050 3850);
FORCEPROP 1 LAST PATH I197
J 0
(-3377 3975);
DISPLAY 0.872340 (-3377 3975);
PAINT GREEN (-3377 3975);
DISPLAY INVISIBLE (-3377 3975);
FORCEADD TAP..1
(-3375 4025);
FORCEPROP 3 LASTPIN (-3425 4025) SIG_NAME M_F_CPU0_SB_DQ<3>
J 0
(-3415 4035);
DISPLAY 0.659574 (-3415 4035);
PAINT MONO (-3415 4035);
DISPLAY INVISIBLE (-3415 4035);
FORCEPROP 1 LASTPIN (-3425 4025) BN 3
J 0
(-3437 4033);
DISPLAY 0.489362 (-3437 4033);
PAINT GREEN (-3437 4033);
FORCEPROP 2 LAST CDS_LIB mstr_standard
J 0
(-3375 4025);
DISPLAY 0.723404 (-3375 4025);
PAINT MONO (-3375 4025);
DISPLAY INVISIBLE (-3375 4025);
FORCEPROP 1 LAST BODY_TYPE PLUMBING
J 0
(-3375 4075);
DISPLAY 0.872340 (-3375 4075);
PAINT GREEN (-3375 4075);
DISPLAY INVISIBLE (-3375 4075);
FORCEPROP 1 LAST HDL_TAP TRUE
J 0
(-3050 3900);
DISPLAY 0.872340 (-3050 3900);
DISPLAY INVISIBLE (-3050 3900);
FORCEPROP 1 LAST PATH I198
J 0
(-3377 4025);
DISPLAY 0.872340 (-3377 4025);
PAINT GREEN (-3377 4025);
DISPLAY INVISIBLE (-3377 4025);
FORCEADD TAP..1
(-3375 4075);
FORCEPROP 3 LASTPIN (-3425 4075) SIG_NAME M_F_CPU0_SB_DQ<2>
J 0
(-3415 4085);
DISPLAY 0.659574 (-3415 4085);
PAINT MONO (-3415 4085);
DISPLAY INVISIBLE (-3415 4085);
FORCEPROP 1 LASTPIN (-3425 4075) BN 2
J 0
(-3437 4083);
DISPLAY 0.489362 (-3437 4083);
PAINT GREEN (-3437 4083);
FORCEPROP 2 LAST CDS_LIB mstr_standard
J 0
(-3375 4075);
DISPLAY 0.723404 (-3375 4075);
PAINT MONO (-3375 4075);
DISPLAY INVISIBLE (-3375 4075);
FORCEPROP 1 LAST BODY_TYPE PLUMBING
J 0
(-3375 4125);
DISPLAY 0.872340 (-3375 4125);
PAINT GREEN (-3375 4125);
DISPLAY INVISIBLE (-3375 4125);
FORCEPROP 1 LAST HDL_TAP TRUE
J 0
(-3050 3950);
DISPLAY 0.872340 (-3050 3950);
DISPLAY INVISIBLE (-3050 3950);
FORCEPROP 1 LAST PATH I199
J 0
(-3377 4075);
DISPLAY 0.872340 (-3377 4075);
PAINT GREEN (-3377 4075);
DISPLAY INVISIBLE (-3377 4075);
FORCEADD TAP..1
(-3375 3875);
FORCEPROP 3 LASTPIN (-3425 3875) SIG_NAME M_F_CPU0_SB_DQ<6>
J 0
(-3415 3885);
DISPLAY 0.659574 (-3415 3885);
PAINT MONO (-3415 3885);
DISPLAY INVISIBLE (-3415 3885);
FORCEPROP 1 LASTPIN (-3425 3875) BN 6
J 0
(-3437 3883);
DISPLAY 0.489362 (-3437 3883);
PAINT GREEN (-3437 3883);
FORCEPROP 2 LAST CDS_LIB mstr_standard
J 0
(-3375 3875);
DISPLAY 0.723404 (-3375 3875);
PAINT MONO (-3375 3875);
DISPLAY INVISIBLE (-3375 3875);
FORCEPROP 1 LAST BODY_TYPE PLUMBING
J 0
(-3375 3925);
DISPLAY 0.872340 (-3375 3925);
PAINT GREEN (-3375 3925);
DISPLAY INVISIBLE (-3375 3925);
FORCEPROP 1 LAST HDL_TAP TRUE
J 0
(-3050 3750);
DISPLAY 0.872340 (-3050 3750);
DISPLAY INVISIBLE (-3050 3750);
FORCEPROP 1 LAST PATH I200
J 0
(-3377 3875);
DISPLAY 0.872340 (-3377 3875);
PAINT GREEN (-3377 3875);
DISPLAY INVISIBLE (-3377 3875);
FORCEADD TAP..1
(-3375 3925);
FORCEPROP 3 LASTPIN (-3425 3925) SIG_NAME M_F_CPU0_SB_DQ<5>
J 0
(-3415 3935);
DISPLAY 0.659574 (-3415 3935);
PAINT MONO (-3415 3935);
DISPLAY INVISIBLE (-3415 3935);
FORCEPROP 1 LASTPIN (-3425 3925) BN 5
J 0
(-3437 3933);
DISPLAY 0.489362 (-3437 3933);
PAINT GREEN (-3437 3933);
FORCEPROP 2 LAST CDS_LIB mstr_standard
J 0
(-3375 3925);
DISPLAY 0.723404 (-3375 3925);
PAINT MONO (-3375 3925);
DISPLAY INVISIBLE (-3375 3925);
FORCEPROP 1 LAST BODY_TYPE PLUMBING
J 0
(-3375 3975);
DISPLAY 0.872340 (-3375 3975);
PAINT GREEN (-3375 3975);
DISPLAY INVISIBLE (-3375 3975);
FORCEPROP 1 LAST HDL_TAP TRUE
J 0
(-3050 3800);
DISPLAY 0.872340 (-3050 3800);
DISPLAY INVISIBLE (-3050 3800);
FORCEPROP 1 LAST PATH I201
J 0
(-3377 3925);
DISPLAY 0.872340 (-3377 3925);
PAINT GREEN (-3377 3925);
DISPLAY INVISIBLE (-3377 3925);
FORCEADD TAP..1
(-3375 3725);
FORCEPROP 3 LASTPIN (-3425 3725) SIG_NAME M_F_CPU0_SB_DQ<8>
J 0
(-3415 3735);
DISPLAY 0.659574 (-3415 3735);
PAINT MONO (-3415 3735);
DISPLAY INVISIBLE (-3415 3735);
FORCEPROP 1 LASTPIN (-3425 3725) BN 8
J 0
(-3437 3733);
DISPLAY 0.489362 (-3437 3733);
PAINT GREEN (-3437 3733);
FORCEPROP 2 LAST CDS_LIB mstr_standard
J 0
(-3375 3725);
DISPLAY 0.723404 (-3375 3725);
PAINT MONO (-3375 3725);
DISPLAY INVISIBLE (-3375 3725);
FORCEPROP 1 LAST BODY_TYPE PLUMBING
J 0
(-3375 3775);
DISPLAY 0.872340 (-3375 3775);
PAINT GREEN (-3375 3775);
DISPLAY INVISIBLE (-3375 3775);
FORCEPROP 1 LAST HDL_TAP TRUE
J 0
(-3050 3600);
DISPLAY 0.872340 (-3050 3600);
DISPLAY INVISIBLE (-3050 3600);
FORCEPROP 1 LAST PATH I202
J 0
(-3377 3725);
DISPLAY 0.872340 (-3377 3725);
PAINT GREEN (-3377 3725);
DISPLAY INVISIBLE (-3377 3725);
FORCEADD TAP..1
(-3375 3825);
FORCEPROP 3 LASTPIN (-3425 3825) SIG_NAME M_F_CPU0_SB_DQ<7>
J 0
(-3415 3835);
DISPLAY 0.659574 (-3415 3835);
PAINT MONO (-3415 3835);
DISPLAY INVISIBLE (-3415 3835);
FORCEPROP 1 LASTPIN (-3425 3825) BN 7
J 0
(-3437 3833);
DISPLAY 0.489362 (-3437 3833);
PAINT GREEN (-3437 3833);
FORCEPROP 2 LAST CDS_LIB mstr_standard
J 0
(-3375 3825);
DISPLAY 0.723404 (-3375 3825);
PAINT MONO (-3375 3825);
DISPLAY INVISIBLE (-3375 3825);
FORCEPROP 1 LAST BODY_TYPE PLUMBING
J 0
(-3375 3875);
DISPLAY 0.872340 (-3375 3875);
PAINT GREEN (-3375 3875);
DISPLAY INVISIBLE (-3375 3875);
FORCEPROP 1 LAST HDL_TAP TRUE
J 0
(-3050 3700);
DISPLAY 0.872340 (-3050 3700);
DISPLAY INVISIBLE (-3050 3700);
FORCEPROP 1 LAST PATH I203
J 0
(-3377 3825);
DISPLAY 0.872340 (-3377 3825);
PAINT GREEN (-3377 3825);
DISPLAY INVISIBLE (-3377 3825);
FORCEADD TAP..1
(-3375 3625);
FORCEPROP 3 LASTPIN (-3425 3625) SIG_NAME M_F_CPU0_SB_DQ<10>
J 0
(-3415 3635);
DISPLAY 0.659574 (-3415 3635);
PAINT MONO (-3415 3635);
DISPLAY INVISIBLE (-3415 3635);
FORCEPROP 1 LASTPIN (-3425 3625) BN 10
J 0
(-3437 3633);
DISPLAY 0.489362 (-3437 3633);
PAINT GREEN (-3437 3633);
FORCEPROP 2 LAST CDS_LIB mstr_standard
J 0
(-3375 3625);
DISPLAY 0.723404 (-3375 3625);
PAINT MONO (-3375 3625);
DISPLAY INVISIBLE (-3375 3625);
FORCEPROP 1 LAST BODY_TYPE PLUMBING
J 0
(-3375 3675);
DISPLAY 0.872340 (-3375 3675);
PAINT GREEN (-3375 3675);
DISPLAY INVISIBLE (-3375 3675);
FORCEPROP 1 LAST HDL_TAP TRUE
J 0
(-3050 3500);
DISPLAY 0.872340 (-3050 3500);
DISPLAY INVISIBLE (-3050 3500);
FORCEPROP 1 LAST PATH I204
J 0
(-3377 3625);
DISPLAY 0.872340 (-3377 3625);
PAINT GREEN (-3377 3625);
DISPLAY INVISIBLE (-3377 3625);
FORCEADD TAP..1
(-3375 3675);
FORCEPROP 3 LASTPIN (-3425 3675) SIG_NAME M_F_CPU0_SB_DQ<9>
J 0
(-3415 3685);
DISPLAY 0.659574 (-3415 3685);
PAINT MONO (-3415 3685);
DISPLAY INVISIBLE (-3415 3685);
FORCEPROP 1 LASTPIN (-3425 3675) BN 9
J 0
(-3437 3683);
DISPLAY 0.489362 (-3437 3683);
PAINT GREEN (-3437 3683);
FORCEPROP 2 LAST CDS_LIB mstr_standard
J 0
(-3375 3675);
DISPLAY 0.723404 (-3375 3675);
PAINT MONO (-3375 3675);
DISPLAY INVISIBLE (-3375 3675);
FORCEPROP 1 LAST BODY_TYPE PLUMBING
J 0
(-3375 3725);
DISPLAY 0.872340 (-3375 3725);
PAINT GREEN (-3375 3725);
DISPLAY INVISIBLE (-3375 3725);
FORCEPROP 1 LAST HDL_TAP TRUE
J 0
(-3050 3550);
DISPLAY 0.872340 (-3050 3550);
DISPLAY INVISIBLE (-3050 3550);
FORCEPROP 1 LAST PATH I205
J 0
(-3377 3675);
DISPLAY 0.872340 (-3377 3675);
PAINT GREEN (-3377 3675);
DISPLAY INVISIBLE (-3377 3675);
FORCEADD TAP..1
(-3375 3475);
FORCEPROP 3 LASTPIN (-3425 3475) SIG_NAME M_F_CPU0_SB_DQ<13>
J 0
(-3415 3485);
DISPLAY 0.659574 (-3415 3485);
PAINT MONO (-3415 3485);
DISPLAY INVISIBLE (-3415 3485);
FORCEPROP 1 LASTPIN (-3425 3475) BN 13
J 0
(-3437 3483);
DISPLAY 0.489362 (-3437 3483);
PAINT GREEN (-3437 3483);
FORCEPROP 2 LAST CDS_LIB mstr_standard
J 0
(-3375 3475);
DISPLAY 0.723404 (-3375 3475);
PAINT MONO (-3375 3475);
DISPLAY INVISIBLE (-3375 3475);
FORCEPROP 1 LAST BODY_TYPE PLUMBING
J 0
(-3375 3525);
DISPLAY 0.872340 (-3375 3525);
PAINT GREEN (-3375 3525);
DISPLAY INVISIBLE (-3375 3525);
FORCEPROP 1 LAST HDL_TAP TRUE
J 0
(-3050 3350);
DISPLAY 0.872340 (-3050 3350);
DISPLAY INVISIBLE (-3050 3350);
FORCEPROP 1 LAST PATH I206
J 0
(-3377 3475);
DISPLAY 0.872340 (-3377 3475);
PAINT GREEN (-3377 3475);
DISPLAY INVISIBLE (-3377 3475);
FORCEADD TAP..1
(-3375 3525);
FORCEPROP 3 LASTPIN (-3425 3525) SIG_NAME M_F_CPU0_SB_DQ<12>
J 0
(-3415 3535);
DISPLAY 0.659574 (-3415 3535);
PAINT MONO (-3415 3535);
DISPLAY INVISIBLE (-3415 3535);
FORCEPROP 1 LASTPIN (-3425 3525) BN 12
J 0
(-3437 3533);
DISPLAY 0.489362 (-3437 3533);
PAINT GREEN (-3437 3533);
FORCEPROP 2 LAST CDS_LIB mstr_standard
J 0
(-3375 3525);
DISPLAY 0.723404 (-3375 3525);
PAINT MONO (-3375 3525);
DISPLAY INVISIBLE (-3375 3525);
FORCEPROP 1 LAST BODY_TYPE PLUMBING
J 0
(-3375 3575);
DISPLAY 0.872340 (-3375 3575);
PAINT GREEN (-3375 3575);
DISPLAY INVISIBLE (-3375 3575);
FORCEPROP 1 LAST HDL_TAP TRUE
J 0
(-3050 3400);
DISPLAY 0.872340 (-3050 3400);
DISPLAY INVISIBLE (-3050 3400);
FORCEPROP 1 LAST PATH I207
J 0
(-3377 3525);
DISPLAY 0.872340 (-3377 3525);
PAINT GREEN (-3377 3525);
DISPLAY INVISIBLE (-3377 3525);
FORCEADD TAP..1
(-3375 3575);
FORCEPROP 3 LASTPIN (-3425 3575) SIG_NAME M_F_CPU0_SB_DQ<11>
J 0
(-3415 3585);
DISPLAY 0.659574 (-3415 3585);
PAINT MONO (-3415 3585);
DISPLAY INVISIBLE (-3415 3585);
FORCEPROP 1 LASTPIN (-3425 3575) BN 11
J 0
(-3437 3583);
DISPLAY 0.489362 (-3437 3583);
PAINT GREEN (-3437 3583);
FORCEPROP 2 LAST CDS_LIB mstr_standard
J 0
(-3375 3575);
DISPLAY 0.723404 (-3375 3575);
PAINT MONO (-3375 3575);
DISPLAY INVISIBLE (-3375 3575);
FORCEPROP 1 LAST BODY_TYPE PLUMBING
J 0
(-3375 3625);
DISPLAY 0.872340 (-3375 3625);
PAINT GREEN (-3375 3625);
DISPLAY INVISIBLE (-3375 3625);
FORCEPROP 1 LAST HDL_TAP TRUE
J 0
(-3050 3450);
DISPLAY 0.872340 (-3050 3450);
DISPLAY INVISIBLE (-3050 3450);
FORCEPROP 1 LAST PATH I208
J 0
(-3377 3575);
DISPLAY 0.872340 (-3377 3575);
PAINT GREEN (-3377 3575);
DISPLAY INVISIBLE (-3377 3575);
FORCEADD TAP..1
(-3375 3425);
FORCEPROP 3 LASTPIN (-3425 3425) SIG_NAME M_F_CPU0_SB_DQ<14>
J 0
(-3415 3435);
DISPLAY 0.659574 (-3415 3435);
PAINT MONO (-3415 3435);
DISPLAY INVISIBLE (-3415 3435);
FORCEPROP 1 LASTPIN (-3425 3425) BN 14
J 0
(-3437 3433);
DISPLAY 0.489362 (-3437 3433);
PAINT GREEN (-3437 3433);
FORCEPROP 2 LAST CDS_LIB mstr_standard
J 0
(-3375 3425);
DISPLAY 0.723404 (-3375 3425);
PAINT MONO (-3375 3425);
DISPLAY INVISIBLE (-3375 3425);
FORCEPROP 1 LAST BODY_TYPE PLUMBING
J 0
(-3375 3475);
DISPLAY 0.872340 (-3375 3475);
PAINT GREEN (-3375 3475);
DISPLAY INVISIBLE (-3375 3475);
FORCEPROP 1 LAST HDL_TAP TRUE
J 0
(-3050 3300);
DISPLAY 0.872340 (-3050 3300);
DISPLAY INVISIBLE (-3050 3300);
FORCEPROP 1 LAST PATH I209
J 0
(-3377 3425);
DISPLAY 0.872340 (-3377 3425);
PAINT GREEN (-3377 3425);
DISPLAY INVISIBLE (-3377 3425);
FORCEADD TAP..1
(-3375 3375);
FORCEPROP 3 LASTPIN (-3425 3375) SIG_NAME M_F_CPU0_SB_DQ<15>
J 0
(-3415 3385);
DISPLAY 0.659574 (-3415 3385);
PAINT MONO (-3415 3385);
DISPLAY INVISIBLE (-3415 3385);
FORCEPROP 1 LASTPIN (-3425 3375) BN 15
J 0
(-3437 3383);
DISPLAY 0.489362 (-3437 3383);
PAINT GREEN (-3437 3383);
FORCEPROP 2 LAST CDS_LIB mstr_standard
J 0
(-3375 3375);
DISPLAY 0.723404 (-3375 3375);
PAINT MONO (-3375 3375);
DISPLAY INVISIBLE (-3375 3375);
FORCEPROP 1 LAST BODY_TYPE PLUMBING
J 0
(-3375 3425);
DISPLAY 0.872340 (-3375 3425);
PAINT GREEN (-3375 3425);
DISPLAY INVISIBLE (-3375 3425);
FORCEPROP 1 LAST HDL_TAP TRUE
J 0
(-3050 3250);
DISPLAY 0.872340 (-3050 3250);
DISPLAY INVISIBLE (-3050 3250);
FORCEPROP 1 LAST PATH I210
J 0
(-3377 3375);
DISPLAY 0.872340 (-3377 3375);
PAINT GREEN (-3377 3375);
DISPLAY INVISIBLE (-3377 3375);
FORCEADD TAP..1
(-3375 3275);
FORCEPROP 3 LASTPIN (-3425 3275) SIG_NAME M_F_CPU0_SB_DQ<16>
J 0
(-3415 3285);
DISPLAY 0.659574 (-3415 3285);
PAINT MONO (-3415 3285);
DISPLAY INVISIBLE (-3415 3285);
FORCEPROP 1 LASTPIN (-3425 3275) BN 16
J 0
(-3437 3283);
DISPLAY 0.489362 (-3437 3283);
PAINT GREEN (-3437 3283);
FORCEPROP 2 LAST CDS_LIB mstr_standard
J 0
(-3375 3275);
DISPLAY 0.723404 (-3375 3275);
PAINT MONO (-3375 3275);
DISPLAY INVISIBLE (-3375 3275);
FORCEPROP 1 LAST BODY_TYPE PLUMBING
J 0
(-3375 3325);
DISPLAY 0.872340 (-3375 3325);
PAINT GREEN (-3375 3325);
DISPLAY INVISIBLE (-3375 3325);
FORCEPROP 1 LAST HDL_TAP TRUE
J 0
(-3050 3150);
DISPLAY 0.872340 (-3050 3150);
DISPLAY INVISIBLE (-3050 3150);
FORCEPROP 1 LAST PATH I211
J 0
(-3377 3275);
DISPLAY 0.872340 (-3377 3275);
PAINT GREEN (-3377 3275);
DISPLAY INVISIBLE (-3377 3275);
FORCEADD TAP..1
(-3375 3225);
FORCEPROP 3 LASTPIN (-3425 3225) SIG_NAME M_F_CPU0_SB_DQ<17>
J 0
(-3415 3235);
DISPLAY 0.659574 (-3415 3235);
PAINT MONO (-3415 3235);
DISPLAY INVISIBLE (-3415 3235);
FORCEPROP 1 LASTPIN (-3425 3225) BN 17
J 0
(-3437 3233);
DISPLAY 0.489362 (-3437 3233);
PAINT GREEN (-3437 3233);
FORCEPROP 2 LAST CDS_LIB mstr_standard
J 0
(-3375 3225);
DISPLAY 0.723404 (-3375 3225);
PAINT MONO (-3375 3225);
DISPLAY INVISIBLE (-3375 3225);
FORCEPROP 1 LAST BODY_TYPE PLUMBING
J 0
(-3375 3275);
DISPLAY 0.872340 (-3375 3275);
PAINT GREEN (-3375 3275);
DISPLAY INVISIBLE (-3375 3275);
FORCEPROP 1 LAST HDL_TAP TRUE
J 0
(-3050 3100);
DISPLAY 0.872340 (-3050 3100);
DISPLAY INVISIBLE (-3050 3100);
FORCEPROP 1 LAST PATH I212
J 0
(-3377 3225);
DISPLAY 0.872340 (-3377 3225);
PAINT GREEN (-3377 3225);
DISPLAY INVISIBLE (-3377 3225);
FORCEADD TAP..1
(-3375 3075);
FORCEPROP 3 LASTPIN (-3425 3075) SIG_NAME M_F_CPU0_SB_DQ<20>
J 0
(-3415 3085);
DISPLAY 0.659574 (-3415 3085);
PAINT MONO (-3415 3085);
DISPLAY INVISIBLE (-3415 3085);
FORCEPROP 1 LASTPIN (-3425 3075) BN 20
J 0
(-3437 3083);
DISPLAY 0.489362 (-3437 3083);
PAINT GREEN (-3437 3083);
FORCEPROP 2 LAST CDS_LIB mstr_standard
J 0
(-3375 3075);
DISPLAY 0.723404 (-3375 3075);
PAINT MONO (-3375 3075);
DISPLAY INVISIBLE (-3375 3075);
FORCEPROP 1 LAST BODY_TYPE PLUMBING
J 0
(-3375 3125);
DISPLAY 0.872340 (-3375 3125);
PAINT GREEN (-3375 3125);
DISPLAY INVISIBLE (-3375 3125);
FORCEPROP 1 LAST HDL_TAP TRUE
J 0
(-3050 2950);
DISPLAY 0.872340 (-3050 2950);
DISPLAY INVISIBLE (-3050 2950);
FORCEPROP 1 LAST PATH I213
J 0
(-3377 3075);
DISPLAY 0.872340 (-3377 3075);
PAINT GREEN (-3377 3075);
DISPLAY INVISIBLE (-3377 3075);
FORCEADD TAP..1
(-3375 3125);
FORCEPROP 3 LASTPIN (-3425 3125) SIG_NAME M_F_CPU0_SB_DQ<19>
J 0
(-3415 3135);
DISPLAY 0.659574 (-3415 3135);
PAINT MONO (-3415 3135);
DISPLAY INVISIBLE (-3415 3135);
FORCEPROP 1 LASTPIN (-3425 3125) BN 19
J 0
(-3437 3133);
DISPLAY 0.489362 (-3437 3133);
PAINT GREEN (-3437 3133);
FORCEPROP 2 LAST CDS_LIB mstr_standard
J 0
(-3375 3125);
DISPLAY 0.723404 (-3375 3125);
PAINT MONO (-3375 3125);
DISPLAY INVISIBLE (-3375 3125);
FORCEPROP 1 LAST BODY_TYPE PLUMBING
J 0
(-3375 3175);
DISPLAY 0.872340 (-3375 3175);
PAINT GREEN (-3375 3175);
DISPLAY INVISIBLE (-3375 3175);
FORCEPROP 1 LAST HDL_TAP TRUE
J 0
(-3050 3000);
DISPLAY 0.872340 (-3050 3000);
DISPLAY INVISIBLE (-3050 3000);
FORCEPROP 1 LAST PATH I214
J 0
(-3377 3125);
DISPLAY 0.872340 (-3377 3125);
PAINT GREEN (-3377 3125);
DISPLAY INVISIBLE (-3377 3125);
FORCEADD TAP..1
(-3375 3175);
FORCEPROP 3 LASTPIN (-3425 3175) SIG_NAME M_F_CPU0_SB_DQ<18>
J 0
(-3415 3185);
DISPLAY 0.659574 (-3415 3185);
PAINT MONO (-3415 3185);
DISPLAY INVISIBLE (-3415 3185);
FORCEPROP 1 LASTPIN (-3425 3175) BN 18
J 0
(-3437 3183);
DISPLAY 0.489362 (-3437 3183);
PAINT GREEN (-3437 3183);
FORCEPROP 2 LAST CDS_LIB mstr_standard
J 0
(-3375 3175);
DISPLAY 0.723404 (-3375 3175);
PAINT MONO (-3375 3175);
DISPLAY INVISIBLE (-3375 3175);
FORCEPROP 1 LAST BODY_TYPE PLUMBING
J 0
(-3375 3225);
DISPLAY 0.872340 (-3375 3225);
PAINT GREEN (-3375 3225);
DISPLAY INVISIBLE (-3375 3225);
FORCEPROP 1 LAST HDL_TAP TRUE
J 0
(-3050 3050);
DISPLAY 0.872340 (-3050 3050);
DISPLAY INVISIBLE (-3050 3050);
FORCEPROP 1 LAST PATH I215
J 0
(-3377 3175);
DISPLAY 0.872340 (-3377 3175);
PAINT GREEN (-3377 3175);
DISPLAY INVISIBLE (-3377 3175);
FORCEADD TAP..1
(-3375 2975);
FORCEPROP 3 LASTPIN (-3425 2975) SIG_NAME M_F_CPU0_SB_DQ<22>
J 0
(-3415 2985);
DISPLAY 0.659574 (-3415 2985);
PAINT MONO (-3415 2985);
DISPLAY INVISIBLE (-3415 2985);
FORCEPROP 1 LASTPIN (-3425 2975) BN 22
J 0
(-3437 2983);
DISPLAY 0.489362 (-3437 2983);
PAINT GREEN (-3437 2983);
FORCEPROP 2 LAST CDS_LIB mstr_standard
J 0
(-3375 2975);
DISPLAY 0.723404 (-3375 2975);
PAINT MONO (-3375 2975);
DISPLAY INVISIBLE (-3375 2975);
FORCEPROP 1 LAST BODY_TYPE PLUMBING
J 0
(-3375 3025);
DISPLAY 0.872340 (-3375 3025);
PAINT GREEN (-3375 3025);
DISPLAY INVISIBLE (-3375 3025);
FORCEPROP 1 LAST HDL_TAP TRUE
J 0
(-3050 2850);
DISPLAY 0.872340 (-3050 2850);
DISPLAY INVISIBLE (-3050 2850);
FORCEPROP 1 LAST PATH I216
J 0
(-3377 2975);
DISPLAY 0.872340 (-3377 2975);
PAINT GREEN (-3377 2975);
DISPLAY INVISIBLE (-3377 2975);
FORCEADD TAP..1
(-3375 3025);
FORCEPROP 3 LASTPIN (-3425 3025) SIG_NAME M_F_CPU0_SB_DQ<21>
J 0
(-3415 3035);
DISPLAY 0.659574 (-3415 3035);
PAINT MONO (-3415 3035);
DISPLAY INVISIBLE (-3415 3035);
FORCEPROP 1 LASTPIN (-3425 3025) BN 21
J 0
(-3437 3033);
DISPLAY 0.489362 (-3437 3033);
PAINT GREEN (-3437 3033);
FORCEPROP 2 LAST CDS_LIB mstr_standard
J 0
(-3375 3025);
DISPLAY 0.723404 (-3375 3025);
PAINT MONO (-3375 3025);
DISPLAY INVISIBLE (-3375 3025);
FORCEPROP 1 LAST BODY_TYPE PLUMBING
J 0
(-3375 3075);
DISPLAY 0.872340 (-3375 3075);
PAINT GREEN (-3375 3075);
DISPLAY INVISIBLE (-3375 3075);
FORCEPROP 1 LAST HDL_TAP TRUE
J 0
(-3050 2900);
DISPLAY 0.872340 (-3050 2900);
DISPLAY INVISIBLE (-3050 2900);
FORCEPROP 1 LAST PATH I217
J 0
(-3377 3025);
DISPLAY 0.872340 (-3377 3025);
PAINT GREEN (-3377 3025);
DISPLAY INVISIBLE (-3377 3025);
FORCEADD TAP..1
(-3375 2825);
FORCEPROP 3 LASTPIN (-3425 2825) SIG_NAME M_F_CPU0_SB_DQ<24>
J 0
(-3415 2835);
DISPLAY 0.659574 (-3415 2835);
PAINT MONO (-3415 2835);
DISPLAY INVISIBLE (-3415 2835);
FORCEPROP 1 LASTPIN (-3425 2825) BN 24
J 0
(-3437 2833);
DISPLAY 0.489362 (-3437 2833);
PAINT GREEN (-3437 2833);
FORCEPROP 2 LAST CDS_LIB mstr_standard
J 0
(-3375 2825);
DISPLAY 0.723404 (-3375 2825);
PAINT MONO (-3375 2825);
DISPLAY INVISIBLE (-3375 2825);
FORCEPROP 1 LAST BODY_TYPE PLUMBING
J 0
(-3375 2875);
DISPLAY 0.872340 (-3375 2875);
PAINT GREEN (-3375 2875);
DISPLAY INVISIBLE (-3375 2875);
FORCEPROP 1 LAST HDL_TAP TRUE
J 0
(-3050 2700);
DISPLAY 0.872340 (-3050 2700);
DISPLAY INVISIBLE (-3050 2700);
FORCEPROP 1 LAST PATH I218
J 0
(-3377 2825);
DISPLAY 0.872340 (-3377 2825);
PAINT GREEN (-3377 2825);
DISPLAY INVISIBLE (-3377 2825);
FORCEADD TAP..1
(-3375 2925);
FORCEPROP 3 LASTPIN (-3425 2925) SIG_NAME M_F_CPU0_SB_DQ<23>
J 0
(-3415 2935);
DISPLAY 0.659574 (-3415 2935);
PAINT MONO (-3415 2935);
DISPLAY INVISIBLE (-3415 2935);
FORCEPROP 1 LASTPIN (-3425 2925) BN 23
J 0
(-3437 2933);
DISPLAY 0.489362 (-3437 2933);
PAINT GREEN (-3437 2933);
FORCEPROP 2 LAST CDS_LIB mstr_standard
J 0
(-3375 2925);
DISPLAY 0.723404 (-3375 2925);
PAINT MONO (-3375 2925);
DISPLAY INVISIBLE (-3375 2925);
FORCEPROP 1 LAST BODY_TYPE PLUMBING
J 0
(-3375 2975);
DISPLAY 0.872340 (-3375 2975);
PAINT GREEN (-3375 2975);
DISPLAY INVISIBLE (-3375 2975);
FORCEPROP 1 LAST HDL_TAP TRUE
J 0
(-3050 2800);
DISPLAY 0.872340 (-3050 2800);
DISPLAY INVISIBLE (-3050 2800);
FORCEPROP 1 LAST PATH I219
J 0
(-3377 2925);
DISPLAY 0.872340 (-3377 2925);
PAINT GREEN (-3377 2925);
DISPLAY INVISIBLE (-3377 2925);
FORCEADD TAP..1
(-3375 2775);
FORCEPROP 3 LASTPIN (-3425 2775) SIG_NAME M_F_CPU0_SB_DQ<25>
J 0
(-3415 2785);
DISPLAY 0.659574 (-3415 2785);
PAINT MONO (-3415 2785);
DISPLAY INVISIBLE (-3415 2785);
FORCEPROP 1 LASTPIN (-3425 2775) BN 25
J 0
(-3437 2783);
DISPLAY 0.489362 (-3437 2783);
PAINT GREEN (-3437 2783);
FORCEPROP 2 LAST CDS_LIB mstr_standard
J 0
(-3375 2775);
DISPLAY 0.723404 (-3375 2775);
PAINT MONO (-3375 2775);
DISPLAY INVISIBLE (-3375 2775);
FORCEPROP 1 LAST BODY_TYPE PLUMBING
J 0
(-3375 2825);
DISPLAY 0.872340 (-3375 2825);
PAINT GREEN (-3375 2825);
DISPLAY INVISIBLE (-3375 2825);
FORCEPROP 1 LAST HDL_TAP TRUE
J 0
(-3050 2650);
DISPLAY 0.872340 (-3050 2650);
DISPLAY INVISIBLE (-3050 2650);
FORCEPROP 1 LAST PATH I220
J 0
(-3377 2775);
DISPLAY 0.872340 (-3377 2775);
PAINT GREEN (-3377 2775);
DISPLAY INVISIBLE (-3377 2775);
FORCEADD TAP..1
(-3375 2725);
FORCEPROP 3 LASTPIN (-3425 2725) SIG_NAME M_F_CPU0_SB_DQ<26>
J 0
(-3415 2735);
DISPLAY 0.659574 (-3415 2735);
PAINT MONO (-3415 2735);
DISPLAY INVISIBLE (-3415 2735);
FORCEPROP 1 LASTPIN (-3425 2725) BN 26
J 0
(-3437 2733);
DISPLAY 0.489362 (-3437 2733);
PAINT GREEN (-3437 2733);
FORCEPROP 2 LAST CDS_LIB mstr_standard
J 0
(-3375 2725);
DISPLAY 0.723404 (-3375 2725);
PAINT MONO (-3375 2725);
DISPLAY INVISIBLE (-3375 2725);
FORCEPROP 1 LAST BODY_TYPE PLUMBING
J 0
(-3375 2775);
DISPLAY 0.872340 (-3375 2775);
PAINT GREEN (-3375 2775);
DISPLAY INVISIBLE (-3375 2775);
FORCEPROP 1 LAST HDL_TAP TRUE
J 0
(-3050 2600);
DISPLAY 0.872340 (-3050 2600);
DISPLAY INVISIBLE (-3050 2600);
FORCEPROP 1 LAST PATH I221
J 0
(-3377 2725);
DISPLAY 0.872340 (-3377 2725);
PAINT GREEN (-3377 2725);
DISPLAY INVISIBLE (-3377 2725);
FORCEADD TAP..1
(-3375 2575);
FORCEPROP 3 LASTPIN (-3425 2575) SIG_NAME M_F_CPU0_SB_DQ<29>
J 0
(-3415 2585);
DISPLAY 0.659574 (-3415 2585);
PAINT MONO (-3415 2585);
DISPLAY INVISIBLE (-3415 2585);
FORCEPROP 1 LASTPIN (-3425 2575) BN 29
J 0
(-3437 2583);
DISPLAY 0.489362 (-3437 2583);
PAINT GREEN (-3437 2583);
FORCEPROP 2 LAST CDS_LIB mstr_standard
J 0
(-3375 2575);
DISPLAY 0.723404 (-3375 2575);
PAINT MONO (-3375 2575);
DISPLAY INVISIBLE (-3375 2575);
FORCEPROP 1 LAST BODY_TYPE PLUMBING
J 0
(-3375 2625);
DISPLAY 0.872340 (-3375 2625);
PAINT GREEN (-3375 2625);
DISPLAY INVISIBLE (-3375 2625);
FORCEPROP 1 LAST HDL_TAP TRUE
J 0
(-3050 2450);
DISPLAY 0.872340 (-3050 2450);
DISPLAY INVISIBLE (-3050 2450);
FORCEPROP 1 LAST PATH I222
J 0
(-3377 2575);
DISPLAY 0.872340 (-3377 2575);
PAINT GREEN (-3377 2575);
DISPLAY INVISIBLE (-3377 2575);
FORCEADD TAP..1
(-3375 2625);
FORCEPROP 3 LASTPIN (-3425 2625) SIG_NAME M_F_CPU0_SB_DQ<28>
J 0
(-3415 2635);
DISPLAY 0.659574 (-3415 2635);
PAINT MONO (-3415 2635);
DISPLAY INVISIBLE (-3415 2635);
FORCEPROP 1 LASTPIN (-3425 2625) BN 28
J 0
(-3437 2633);
DISPLAY 0.489362 (-3437 2633);
PAINT GREEN (-3437 2633);
FORCEPROP 2 LAST CDS_LIB mstr_standard
J 0
(-3375 2625);
DISPLAY 0.723404 (-3375 2625);
PAINT MONO (-3375 2625);
DISPLAY INVISIBLE (-3375 2625);
FORCEPROP 1 LAST BODY_TYPE PLUMBING
J 0
(-3375 2675);
DISPLAY 0.872340 (-3375 2675);
PAINT GREEN (-3375 2675);
DISPLAY INVISIBLE (-3375 2675);
FORCEPROP 1 LAST HDL_TAP TRUE
J 0
(-3050 2500);
DISPLAY 0.872340 (-3050 2500);
DISPLAY INVISIBLE (-3050 2500);
FORCEPROP 1 LAST PATH I223
J 0
(-3377 2625);
DISPLAY 0.872340 (-3377 2625);
PAINT GREEN (-3377 2625);
DISPLAY INVISIBLE (-3377 2625);
FORCEADD TAP..1
(-3375 2675);
FORCEPROP 3 LASTPIN (-3425 2675) SIG_NAME M_F_CPU0_SB_DQ<27>
J 0
(-3415 2685);
DISPLAY 0.659574 (-3415 2685);
PAINT MONO (-3415 2685);
DISPLAY INVISIBLE (-3415 2685);
FORCEPROP 1 LASTPIN (-3425 2675) BN 27
J 0
(-3437 2683);
DISPLAY 0.489362 (-3437 2683);
PAINT GREEN (-3437 2683);
FORCEPROP 2 LAST CDS_LIB mstr_standard
J 0
(-3375 2675);
DISPLAY 0.723404 (-3375 2675);
PAINT MONO (-3375 2675);
DISPLAY INVISIBLE (-3375 2675);
FORCEPROP 1 LAST BODY_TYPE PLUMBING
J 0
(-3375 2725);
DISPLAY 0.872340 (-3375 2725);
PAINT GREEN (-3375 2725);
DISPLAY INVISIBLE (-3375 2725);
FORCEPROP 1 LAST HDL_TAP TRUE
J 0
(-3050 2550);
DISPLAY 0.872340 (-3050 2550);
DISPLAY INVISIBLE (-3050 2550);
FORCEPROP 1 LAST PATH I224
J 0
(-3377 2675);
DISPLAY 0.872340 (-3377 2675);
PAINT GREEN (-3377 2675);
DISPLAY INVISIBLE (-3377 2675);
FORCEADD TAP..1
(-3375 2525);
FORCEPROP 3 LASTPIN (-3425 2525) SIG_NAME M_F_CPU0_SB_DQ<30>
J 0
(-3415 2535);
DISPLAY 0.659574 (-3415 2535);
PAINT MONO (-3415 2535);
DISPLAY INVISIBLE (-3415 2535);
FORCEPROP 1 LASTPIN (-3425 2525) BN 30
J 0
(-3437 2533);
DISPLAY 0.489362 (-3437 2533);
PAINT GREEN (-3437 2533);
FORCEPROP 2 LAST CDS_LIB mstr_standard
J 0
(-3375 2525);
DISPLAY 0.723404 (-3375 2525);
PAINT MONO (-3375 2525);
DISPLAY INVISIBLE (-3375 2525);
FORCEPROP 1 LAST BODY_TYPE PLUMBING
J 0
(-3375 2575);
DISPLAY 0.872340 (-3375 2575);
PAINT GREEN (-3375 2575);
DISPLAY INVISIBLE (-3375 2575);
FORCEPROP 1 LAST HDL_TAP TRUE
J 0
(-3050 2400);
DISPLAY 0.872340 (-3050 2400);
DISPLAY INVISIBLE (-3050 2400);
FORCEPROP 1 LAST PATH I225
J 0
(-3377 2525);
DISPLAY 0.872340 (-3377 2525);
PAINT GREEN (-3377 2525);
DISPLAY INVISIBLE (-3377 2525);
FORCEADD TAP..1
(-3375 2475);
FORCEPROP 3 LASTPIN (-3425 2475) SIG_NAME M_F_CPU0_SB_DQ<31>
J 0
(-3415 2485);
DISPLAY 0.659574 (-3415 2485);
PAINT MONO (-3415 2485);
DISPLAY INVISIBLE (-3415 2485);
FORCEPROP 1 LASTPIN (-3425 2475) BN 31
J 0
(-3437 2483);
DISPLAY 0.489362 (-3437 2483);
PAINT GREEN (-3437 2483);
FORCEPROP 2 LAST CDS_LIB mstr_standard
J 0
(-3375 2475);
DISPLAY 0.723404 (-3375 2475);
PAINT MONO (-3375 2475);
DISPLAY INVISIBLE (-3375 2475);
FORCEPROP 1 LAST BODY_TYPE PLUMBING
J 0
(-3375 2525);
DISPLAY 0.872340 (-3375 2525);
PAINT GREEN (-3375 2525);
DISPLAY INVISIBLE (-3375 2525);
FORCEPROP 1 LAST HDL_TAP TRUE
J 0
(-3050 2350);
DISPLAY 0.872340 (-3050 2350);
DISPLAY INVISIBLE (-3050 2350);
FORCEPROP 1 LAST PATH I226
J 0
(-3377 2475);
DISPLAY 0.872340 (-3377 2475);
PAINT GREEN (-3377 2475);
DISPLAY INVISIBLE (-3377 2475);
FORCEADD TAP..1
(-3375 2325);
FORCEPROP 3 LASTPIN (-3425 2325) SIG_NAME M_F_CPU0_SA_CB<1>
J 0
(-3415 2335);
DISPLAY 0.659574 (-3415 2335);
PAINT MONO (-3415 2335);
DISPLAY INVISIBLE (-3415 2335);
FORCEPROP 1 LASTPIN (-3425 2325) BN 1
J 0
(-3437 2333);
DISPLAY 0.489362 (-3437 2333);
PAINT GREEN (-3437 2333);
FORCEPROP 2 LAST CDS_LIB mstr_standard
J 2
(-3375 2325);
DISPLAY 0.723404 (-3375 2325);
PAINT MONO (-3375 2325);
DISPLAY INVISIBLE (-3375 2325);
FORCEPROP 1 LAST BODY_TYPE PLUMBING
J 0
(-3375 2375);
DISPLAY 0.872340 (-3375 2375);
PAINT GREEN (-3375 2375);
DISPLAY INVISIBLE (-3375 2375);
FORCEPROP 1 LAST HDL_TAP TRUE
J 0
(-3050 2200);
DISPLAY 0.872340 (-3050 2200);
DISPLAY INVISIBLE (-3050 2200);
FORCEPROP 1 LAST PATH I227
J 0
(-3377 2325);
DISPLAY 0.872340 (-3377 2325);
PAINT GREEN (-3377 2325);
DISPLAY INVISIBLE (-3377 2325);
FORCEADD TAP..1
(-3375 2375);
FORCEPROP 3 LASTPIN (-3425 2375) SIG_NAME M_F_CPU0_SA_CB<0>
J 0
(-3415 2385);
DISPLAY 0.659574 (-3415 2385);
PAINT MONO (-3415 2385);
DISPLAY INVISIBLE (-3415 2385);
FORCEPROP 1 LASTPIN (-3425 2375) BN 0
J 0
(-3437 2383);
DISPLAY 0.489362 (-3437 2383);
PAINT GREEN (-3437 2383);
FORCEPROP 2 LAST CDS_LIB mstr_standard
J 2
(-3375 2375);
DISPLAY 0.723404 (-3375 2375);
PAINT MONO (-3375 2375);
DISPLAY INVISIBLE (-3375 2375);
FORCEPROP 1 LAST BODY_TYPE PLUMBING
J 0
(-3375 2425);
DISPLAY 0.872340 (-3375 2425);
PAINT GREEN (-3375 2425);
DISPLAY INVISIBLE (-3375 2425);
FORCEPROP 1 LAST HDL_TAP TRUE
J 0
(-3050 2250);
DISPLAY 0.872340 (-3050 2250);
DISPLAY INVISIBLE (-3050 2250);
FORCEPROP 1 LAST PATH I228
J 0
(-3377 2375);
DISPLAY 0.872340 (-3377 2375);
PAINT GREEN (-3377 2375);
DISPLAY INVISIBLE (-3377 2375);
FORCEADD TAP..1
(-3375 2275);
FORCEPROP 3 LASTPIN (-3425 2275) SIG_NAME M_F_CPU0_SA_CB<2>
J 0
(-3415 2285);
DISPLAY 0.659574 (-3415 2285);
PAINT MONO (-3415 2285);
DISPLAY INVISIBLE (-3415 2285);
FORCEPROP 1 LASTPIN (-3425 2275) BN 2
J 0
(-3437 2283);
DISPLAY 0.489362 (-3437 2283);
PAINT GREEN (-3437 2283);
FORCEPROP 2 LAST CDS_LIB mstr_standard
J 2
(-3375 2275);
DISPLAY 0.723404 (-3375 2275);
PAINT MONO (-3375 2275);
DISPLAY INVISIBLE (-3375 2275);
FORCEPROP 1 LAST BODY_TYPE PLUMBING
J 0
(-3375 2325);
DISPLAY 0.872340 (-3375 2325);
PAINT GREEN (-3375 2325);
DISPLAY INVISIBLE (-3375 2325);
FORCEPROP 1 LAST HDL_TAP TRUE
J 0
(-3050 2150);
DISPLAY 0.872340 (-3050 2150);
DISPLAY INVISIBLE (-3050 2150);
FORCEPROP 1 LAST PATH I229
J 0
(-3377 2275);
DISPLAY 0.872340 (-3377 2275);
PAINT GREEN (-3377 2275);
DISPLAY INVISIBLE (-3377 2275);
FORCEADD TAP..1
(-3375 2225);
FORCEPROP 3 LASTPIN (-3425 2225) SIG_NAME M_F_CPU0_SA_CB<3>
J 0
(-3415 2235);
DISPLAY 0.659574 (-3415 2235);
PAINT MONO (-3415 2235);
DISPLAY INVISIBLE (-3415 2235);
FORCEPROP 1 LASTPIN (-3425 2225) BN 3
J 0
(-3437 2233);
DISPLAY 0.489362 (-3437 2233);
PAINT GREEN (-3437 2233);
FORCEPROP 2 LAST CDS_LIB mstr_standard
J 2
(-3375 2225);
DISPLAY 0.723404 (-3375 2225);
PAINT MONO (-3375 2225);
DISPLAY INVISIBLE (-3375 2225);
FORCEPROP 1 LAST BODY_TYPE PLUMBING
J 0
(-3375 2275);
DISPLAY 0.872340 (-3375 2275);
PAINT GREEN (-3375 2275);
DISPLAY INVISIBLE (-3375 2275);
FORCEPROP 1 LAST HDL_TAP TRUE
J 0
(-3050 2100);
DISPLAY 0.872340 (-3050 2100);
DISPLAY INVISIBLE (-3050 2100);
FORCEPROP 1 LAST PATH I230
J 0
(-3377 2225);
DISPLAY 0.872340 (-3377 2225);
PAINT GREEN (-3377 2225);
DISPLAY INVISIBLE (-3377 2225);
FORCEADD TAP..1
(-3375 2075);
FORCEPROP 3 LASTPIN (-3425 2075) SIG_NAME M_F_CPU0_SA_CB<6>
J 0
(-3415 2085);
DISPLAY 0.659574 (-3415 2085);
PAINT MONO (-3415 2085);
DISPLAY INVISIBLE (-3415 2085);
FORCEPROP 1 LASTPIN (-3425 2075) BN 6
J 0
(-3437 2083);
DISPLAY 0.489362 (-3437 2083);
PAINT GREEN (-3437 2083);
FORCEPROP 2 LAST CDS_LIB mstr_standard
J 2
(-3375 2075);
DISPLAY 0.723404 (-3375 2075);
PAINT MONO (-3375 2075);
DISPLAY INVISIBLE (-3375 2075);
FORCEPROP 1 LAST BODY_TYPE PLUMBING
J 0
(-3375 2125);
DISPLAY 0.872340 (-3375 2125);
PAINT GREEN (-3375 2125);
DISPLAY INVISIBLE (-3375 2125);
FORCEPROP 1 LAST HDL_TAP TRUE
J 0
(-3050 1950);
DISPLAY 0.872340 (-3050 1950);
DISPLAY INVISIBLE (-3050 1950);
FORCEPROP 1 LAST PATH I231
J 0
(-3377 2075);
DISPLAY 0.872340 (-3377 2075);
PAINT GREEN (-3377 2075);
DISPLAY INVISIBLE (-3377 2075);
FORCEADD TAP..1
(-3375 2125);
FORCEPROP 3 LASTPIN (-3425 2125) SIG_NAME M_F_CPU0_SA_CB<5>
J 0
(-3415 2135);
DISPLAY 0.659574 (-3415 2135);
PAINT MONO (-3415 2135);
DISPLAY INVISIBLE (-3415 2135);
FORCEPROP 1 LASTPIN (-3425 2125) BN 5
J 0
(-3437 2133);
DISPLAY 0.489362 (-3437 2133);
PAINT GREEN (-3437 2133);
FORCEPROP 2 LAST CDS_LIB mstr_standard
J 2
(-3375 2125);
DISPLAY 0.723404 (-3375 2125);
PAINT MONO (-3375 2125);
DISPLAY INVISIBLE (-3375 2125);
FORCEPROP 1 LAST BODY_TYPE PLUMBING
J 0
(-3375 2175);
DISPLAY 0.872340 (-3375 2175);
PAINT GREEN (-3375 2175);
DISPLAY INVISIBLE (-3375 2175);
FORCEPROP 1 LAST HDL_TAP TRUE
J 0
(-3050 2000);
DISPLAY 0.872340 (-3050 2000);
DISPLAY INVISIBLE (-3050 2000);
FORCEPROP 1 LAST PATH I232
J 0
(-3377 2125);
DISPLAY 0.872340 (-3377 2125);
PAINT GREEN (-3377 2125);
DISPLAY INVISIBLE (-3377 2125);
FORCEADD TAP..1
(-3375 2175);
FORCEPROP 3 LASTPIN (-3425 2175) SIG_NAME M_F_CPU0_SA_CB<4>
J 0
(-3415 2185);
DISPLAY 0.659574 (-3415 2185);
PAINT MONO (-3415 2185);
DISPLAY INVISIBLE (-3415 2185);
FORCEPROP 1 LASTPIN (-3425 2175) BN 4
J 0
(-3437 2183);
DISPLAY 0.489362 (-3437 2183);
PAINT GREEN (-3437 2183);
FORCEPROP 2 LAST CDS_LIB mstr_standard
J 2
(-3375 2175);
DISPLAY 0.723404 (-3375 2175);
PAINT MONO (-3375 2175);
DISPLAY INVISIBLE (-3375 2175);
FORCEPROP 1 LAST BODY_TYPE PLUMBING
J 0
(-3375 2225);
DISPLAY 0.872340 (-3375 2225);
PAINT GREEN (-3375 2225);
DISPLAY INVISIBLE (-3375 2225);
FORCEPROP 1 LAST HDL_TAP TRUE
J 0
(-3050 2050);
DISPLAY 0.872340 (-3050 2050);
DISPLAY INVISIBLE (-3050 2050);
FORCEPROP 1 LAST PATH I233
J 0
(-3377 2175);
DISPLAY 0.872340 (-3377 2175);
PAINT GREEN (-3377 2175);
DISPLAY INVISIBLE (-3377 2175);
FORCEADD OFFPAGE..6
R 2
(-2775 1975);
FORCEPROP 2 LAST $XR0 91 
J 0
(-2561 1975);
DISPLAY 0.638298 (-2561 1975);
PAINT MONO (-2561 1975);
FORCEPROP 2 LAST CDS_LIB mstr_standard
J 2
(-2775 1975);
DISPLAY 0.723404 (-2775 1975);
PAINT MONO (-2775 1975);
DISPLAY INVISIBLE (-2775 1975);
FORCEPROP 1 LAST OFFPAGE TRUE
J 2
(-3100 1850);
DISPLAY 0.872340 (-3100 1850);
PAINT GREEN (-3100 1850);
DISPLAY INVISIBLE (-3100 1850);
FORCEPROP 1 LAST COMMENT_BODY TRUE
J 2
(-2875 1900);
DISPLAY 0.872340 (-2875 1900);
PAINT GREEN (-2875 1900);
DISPLAY INVISIBLE (-2875 1900);
FORCEPROP 2 LAST PATH I234
J 0
(-2550 2025);
DISPLAY 1.021277 (-2550 2025);
DISPLAY INVISIBLE (-2550 2025);
FORCEADD TAP..1
(-3375 2025);
FORCEPROP 3 LASTPIN (-3425 2025) SIG_NAME M_F_CPU0_SA_CB<7>
J 0
(-3415 2035);
DISPLAY 0.659574 (-3415 2035);
PAINT MONO (-3415 2035);
DISPLAY INVISIBLE (-3415 2035);
FORCEPROP 1 LASTPIN (-3425 2025) BN 7
J 0
(-3437 2033);
DISPLAY 0.489362 (-3437 2033);
PAINT GREEN (-3437 2033);
FORCEPROP 2 LAST CDS_LIB mstr_standard
J 2
(-3375 2025);
DISPLAY 0.723404 (-3375 2025);
PAINT MONO (-3375 2025);
DISPLAY INVISIBLE (-3375 2025);
FORCEPROP 1 LAST BODY_TYPE PLUMBING
J 0
(-3375 2075);
DISPLAY 0.872340 (-3375 2075);
PAINT GREEN (-3375 2075);
DISPLAY INVISIBLE (-3375 2075);
FORCEPROP 1 LAST HDL_TAP TRUE
J 0
(-3050 1900);
DISPLAY 0.872340 (-3050 1900);
DISPLAY INVISIBLE (-3050 1900);
FORCEPROP 1 LAST PATH I235
J 0
(-3377 2025);
DISPLAY 0.872340 (-3377 2025);
PAINT GREEN (-3377 2025);
DISPLAY INVISIBLE (-3377 2025);
FORCEADD TAP..1
(-3375 1925);
FORCEPROP 3 LASTPIN (-3425 1925) SIG_NAME M_F_CPU0_SB_CB<0>
J 0
(-3415 1935);
DISPLAY 0.659574 (-3415 1935);
PAINT MONO (-3415 1935);
DISPLAY INVISIBLE (-3415 1935);
FORCEPROP 1 LASTPIN (-3425 1925) BN 0
J 0
(-3437 1933);
DISPLAY 0.489362 (-3437 1933);
PAINT GREEN (-3437 1933);
FORCEPROP 2 LAST CDS_LIB mstr_standard
J 2
(-3375 1925);
DISPLAY 0.723404 (-3375 1925);
PAINT MONO (-3375 1925);
DISPLAY INVISIBLE (-3375 1925);
FORCEPROP 1 LAST BODY_TYPE PLUMBING
J 0
(-3375 1975);
DISPLAY 0.872340 (-3375 1975);
PAINT GREEN (-3375 1975);
DISPLAY INVISIBLE (-3375 1975);
FORCEPROP 1 LAST HDL_TAP TRUE
J 0
(-3050 1800);
DISPLAY 0.872340 (-3050 1800);
DISPLAY INVISIBLE (-3050 1800);
FORCEPROP 1 LAST PATH I236
J 0
(-3377 1925);
DISPLAY 0.872340 (-3377 1925);
PAINT GREEN (-3377 1925);
DISPLAY INVISIBLE (-3377 1925);
FORCEADD TAP..1
(-3375 1825);
FORCEPROP 3 LASTPIN (-3425 1825) SIG_NAME M_F_CPU0_SB_CB<2>
J 0
(-3415 1835);
DISPLAY 0.659574 (-3415 1835);
PAINT MONO (-3415 1835);
DISPLAY INVISIBLE (-3415 1835);
FORCEPROP 1 LASTPIN (-3425 1825) BN 2
J 0
(-3437 1833);
DISPLAY 0.489362 (-3437 1833);
PAINT GREEN (-3437 1833);
FORCEPROP 2 LAST CDS_LIB mstr_standard
J 2
(-3375 1825);
DISPLAY 0.723404 (-3375 1825);
PAINT MONO (-3375 1825);
DISPLAY INVISIBLE (-3375 1825);
FORCEPROP 1 LAST BODY_TYPE PLUMBING
J 0
(-3375 1875);
DISPLAY 0.872340 (-3375 1875);
PAINT GREEN (-3375 1875);
DISPLAY INVISIBLE (-3375 1875);
FORCEPROP 1 LAST HDL_TAP TRUE
J 0
(-3050 1700);
DISPLAY 0.872340 (-3050 1700);
DISPLAY INVISIBLE (-3050 1700);
FORCEPROP 1 LAST PATH I237
J 0
(-3377 1825);
DISPLAY 0.872340 (-3377 1825);
PAINT GREEN (-3377 1825);
DISPLAY INVISIBLE (-3377 1825);
FORCEADD TAP..1
(-3375 1875);
FORCEPROP 3 LASTPIN (-3425 1875) SIG_NAME M_F_CPU0_SB_CB<1>
J 0
(-3415 1885);
DISPLAY 0.659574 (-3415 1885);
PAINT MONO (-3415 1885);
DISPLAY INVISIBLE (-3415 1885);
FORCEPROP 1 LASTPIN (-3425 1875) BN 1
J 0
(-3437 1883);
DISPLAY 0.489362 (-3437 1883);
PAINT GREEN (-3437 1883);
FORCEPROP 2 LAST CDS_LIB mstr_standard
J 2
(-3375 1875);
DISPLAY 0.723404 (-3375 1875);
PAINT MONO (-3375 1875);
DISPLAY INVISIBLE (-3375 1875);
FORCEPROP 1 LAST BODY_TYPE PLUMBING
J 0
(-3375 1925);
DISPLAY 0.872340 (-3375 1925);
PAINT GREEN (-3375 1925);
DISPLAY INVISIBLE (-3375 1925);
FORCEPROP 1 LAST HDL_TAP TRUE
J 0
(-3050 1750);
DISPLAY 0.872340 (-3050 1750);
DISPLAY INVISIBLE (-3050 1750);
FORCEPROP 1 LAST PATH I238
J 0
(-3377 1875);
DISPLAY 0.872340 (-3377 1875);
PAINT GREEN (-3377 1875);
DISPLAY INVISIBLE (-3377 1875);
FORCEADD TAP..1
(-3375 1675);
FORCEPROP 3 LASTPIN (-3425 1675) SIG_NAME M_F_CPU0_SB_CB<5>
J 0
(-3415 1685);
DISPLAY 0.659574 (-3415 1685);
PAINT MONO (-3415 1685);
DISPLAY INVISIBLE (-3415 1685);
FORCEPROP 1 LASTPIN (-3425 1675) BN 5
J 0
(-3437 1683);
DISPLAY 0.489362 (-3437 1683);
PAINT GREEN (-3437 1683);
FORCEPROP 2 LAST CDS_LIB mstr_standard
J 2
(-3375 1675);
DISPLAY 0.723404 (-3375 1675);
PAINT MONO (-3375 1675);
DISPLAY INVISIBLE (-3375 1675);
FORCEPROP 1 LAST BODY_TYPE PLUMBING
J 0
(-3375 1725);
DISPLAY 0.872340 (-3375 1725);
PAINT GREEN (-3375 1725);
DISPLAY INVISIBLE (-3375 1725);
FORCEPROP 1 LAST HDL_TAP TRUE
J 0
(-3050 1550);
DISPLAY 0.872340 (-3050 1550);
DISPLAY INVISIBLE (-3050 1550);
FORCEPROP 1 LAST PATH I239
J 0
(-3377 1675);
DISPLAY 0.872340 (-3377 1675);
PAINT GREEN (-3377 1675);
DISPLAY INVISIBLE (-3377 1675);
FORCEADD TAP..1
(-3375 1725);
FORCEPROP 3 LASTPIN (-3425 1725) SIG_NAME M_F_CPU0_SB_CB<4>
J 0
(-3415 1735);
DISPLAY 0.659574 (-3415 1735);
PAINT MONO (-3415 1735);
DISPLAY INVISIBLE (-3415 1735);
FORCEPROP 1 LASTPIN (-3425 1725) BN 4
J 0
(-3437 1733);
DISPLAY 0.489362 (-3437 1733);
PAINT GREEN (-3437 1733);
FORCEPROP 2 LAST CDS_LIB mstr_standard
J 2
(-3375 1725);
DISPLAY 0.723404 (-3375 1725);
PAINT MONO (-3375 1725);
DISPLAY INVISIBLE (-3375 1725);
FORCEPROP 1 LAST BODY_TYPE PLUMBING
J 0
(-3375 1775);
DISPLAY 0.872340 (-3375 1775);
PAINT GREEN (-3375 1775);
DISPLAY INVISIBLE (-3375 1775);
FORCEPROP 1 LAST HDL_TAP TRUE
J 0
(-3050 1600);
DISPLAY 0.872340 (-3050 1600);
DISPLAY INVISIBLE (-3050 1600);
FORCEPROP 1 LAST PATH I240
J 0
(-3377 1725);
DISPLAY 0.872340 (-3377 1725);
PAINT GREEN (-3377 1725);
DISPLAY INVISIBLE (-3377 1725);
FORCEADD TAP..1
(-3375 1775);
FORCEPROP 3 LASTPIN (-3425 1775) SIG_NAME M_F_CPU0_SB_CB<3>
J 0
(-3415 1785);
DISPLAY 0.659574 (-3415 1785);
PAINT MONO (-3415 1785);
DISPLAY INVISIBLE (-3415 1785);
FORCEPROP 1 LASTPIN (-3425 1775) BN 3
J 0
(-3437 1783);
DISPLAY 0.489362 (-3437 1783);
PAINT GREEN (-3437 1783);
FORCEPROP 2 LAST CDS_LIB mstr_standard
J 2
(-3375 1775);
DISPLAY 0.723404 (-3375 1775);
PAINT MONO (-3375 1775);
DISPLAY INVISIBLE (-3375 1775);
FORCEPROP 1 LAST BODY_TYPE PLUMBING
J 0
(-3375 1825);
DISPLAY 0.872340 (-3375 1825);
PAINT GREEN (-3375 1825);
DISPLAY INVISIBLE (-3375 1825);
FORCEPROP 1 LAST HDL_TAP TRUE
J 0
(-3050 1650);
DISPLAY 0.872340 (-3050 1650);
DISPLAY INVISIBLE (-3050 1650);
FORCEPROP 1 LAST PATH I241
J 0
(-3377 1775);
DISPLAY 0.872340 (-3377 1775);
PAINT GREEN (-3377 1775);
DISPLAY INVISIBLE (-3377 1775);
FORCEADD TAP..1
(-3375 1575);
FORCEPROP 3 LASTPIN (-3425 1575) SIG_NAME M_F_CPU0_SB_CB<7>
J 0
(-3415 1585);
DISPLAY 0.659574 (-3415 1585);
PAINT MONO (-3415 1585);
DISPLAY INVISIBLE (-3415 1585);
FORCEPROP 1 LASTPIN (-3425 1575) BN 7
J 0
(-3437 1583);
DISPLAY 0.489362 (-3437 1583);
PAINT GREEN (-3437 1583);
FORCEPROP 2 LAST CDS_LIB mstr_standard
J 2
(-3375 1575);
DISPLAY 0.723404 (-3375 1575);
PAINT MONO (-3375 1575);
DISPLAY INVISIBLE (-3375 1575);
FORCEPROP 1 LAST BODY_TYPE PLUMBING
J 0
(-3375 1625);
DISPLAY 0.872340 (-3375 1625);
PAINT GREEN (-3375 1625);
DISPLAY INVISIBLE (-3375 1625);
FORCEPROP 1 LAST HDL_TAP TRUE
J 0
(-3050 1450);
DISPLAY 0.872340 (-3050 1450);
DISPLAY INVISIBLE (-3050 1450);
FORCEPROP 1 LAST PATH I242
J 0
(-3377 1575);
DISPLAY 0.872340 (-3377 1575);
PAINT GREEN (-3377 1575);
DISPLAY INVISIBLE (-3377 1575);
FORCEADD TAP..1
(-3375 1625);
FORCEPROP 3 LASTPIN (-3425 1625) SIG_NAME M_F_CPU0_SB_CB<6>
J 0
(-3415 1635);
DISPLAY 0.659574 (-3415 1635);
PAINT MONO (-3415 1635);
DISPLAY INVISIBLE (-3415 1635);
FORCEPROP 1 LASTPIN (-3425 1625) BN 6
J 0
(-3437 1633);
DISPLAY 0.489362 (-3437 1633);
PAINT GREEN (-3437 1633);
FORCEPROP 2 LAST CDS_LIB mstr_standard
J 2
(-3375 1625);
DISPLAY 0.723404 (-3375 1625);
PAINT MONO (-3375 1625);
DISPLAY INVISIBLE (-3375 1625);
FORCEPROP 1 LAST BODY_TYPE PLUMBING
J 0
(-3375 1675);
DISPLAY 0.872340 (-3375 1675);
PAINT GREEN (-3375 1675);
DISPLAY INVISIBLE (-3375 1675);
FORCEPROP 1 LAST HDL_TAP TRUE
J 0
(-3050 1500);
DISPLAY 0.872340 (-3050 1500);
DISPLAY INVISIBLE (-3050 1500);
FORCEPROP 1 LAST PATH I243
J 0
(-3377 1625);
DISPLAY 0.872340 (-3377 1625);
PAINT GREEN (-3377 1625);
DISPLAY INVISIBLE (-3377 1625);
FORCEADD TAP..1
R 2
(-5800 5975);
FORCEPROP 3 LASTPIN (-5750 5975) SIG_NAME M_F_CPU0_SA_DQS_DP<0>
J 0
(-5740 5985);
DISPLAY 0.659574 (-5740 5985);
PAINT MONO (-5740 5985);
DISPLAY INVISIBLE (-5740 5985);
FORCEPROP 1 LASTPIN (-5750 5975) BN 0
J 2
(-5738 5983);
DISPLAY 0.489362 (-5738 5983);
PAINT GREEN (-5738 5983);
FORCEPROP 2 LAST CDS_LIB mstr_standard
J 2
(-5800 5975);
DISPLAY 0.723404 (-5800 5975);
PAINT MONO (-5800 5975);
DISPLAY INVISIBLE (-5800 5975);
FORCEPROP 1 LAST BODY_TYPE PLUMBING
J 2
(-5800 6025);
DISPLAY 0.872340 (-5800 6025);
PAINT GREEN (-5800 6025);
DISPLAY INVISIBLE (-5800 6025);
FORCEPROP 1 LAST HDL_TAP TRUE
J 2
(-6125 5850);
DISPLAY 0.872340 (-6125 5850);
DISPLAY INVISIBLE (-6125 5850);
FORCEPROP 1 LAST PATH I244
J 2
(-5798 5975);
DISPLAY 0.872340 (-5798 5975);
PAINT GREEN (-5798 5975);
DISPLAY INVISIBLE (-5798 5975);
FORCEADD TAP..1
R 2
(-5800 5875);
FORCEPROP 3 LASTPIN (-5750 5875) SIG_NAME M_F_CPU0_SA_DQS_DP<1>
J 0
(-5740 5885);
DISPLAY 0.659574 (-5740 5885);
PAINT MONO (-5740 5885);
DISPLAY INVISIBLE (-5740 5885);
FORCEPROP 1 LASTPIN (-5750 5875) BN 1
J 2
(-5738 5883);
DISPLAY 0.489362 (-5738 5883);
PAINT GREEN (-5738 5883);
FORCEPROP 2 LAST CDS_LIB mstr_standard
J 2
(-5800 5875);
DISPLAY 0.723404 (-5800 5875);
PAINT MONO (-5800 5875);
DISPLAY INVISIBLE (-5800 5875);
FORCEPROP 1 LAST BODY_TYPE PLUMBING
J 2
(-5800 5925);
DISPLAY 0.872340 (-5800 5925);
PAINT GREEN (-5800 5925);
DISPLAY INVISIBLE (-5800 5925);
FORCEPROP 1 LAST HDL_TAP TRUE
J 2
(-6125 5750);
DISPLAY 0.872340 (-6125 5750);
DISPLAY INVISIBLE (-6125 5750);
FORCEPROP 1 LAST PATH I245
J 2
(-5798 5875);
DISPLAY 0.872340 (-5798 5875);
PAINT GREEN (-5798 5875);
DISPLAY INVISIBLE (-5798 5875);
FORCEADD TAP..1
R 2
(-5800 5775);
FORCEPROP 3 LASTPIN (-5750 5775) SIG_NAME M_F_CPU0_SA_DQS_DP<2>
J 0
(-5740 5785);
DISPLAY 0.659574 (-5740 5785);
PAINT MONO (-5740 5785);
DISPLAY INVISIBLE (-5740 5785);
FORCEPROP 1 LASTPIN (-5750 5775) BN 2
J 2
(-5738 5783);
DISPLAY 0.489362 (-5738 5783);
PAINT GREEN (-5738 5783);
FORCEPROP 2 LAST CDS_LIB mstr_standard
J 2
(-5800 5775);
DISPLAY 0.723404 (-5800 5775);
PAINT MONO (-5800 5775);
DISPLAY INVISIBLE (-5800 5775);
FORCEPROP 1 LAST BODY_TYPE PLUMBING
J 2
(-5800 5825);
DISPLAY 0.872340 (-5800 5825);
PAINT GREEN (-5800 5825);
DISPLAY INVISIBLE (-5800 5825);
FORCEPROP 1 LAST HDL_TAP TRUE
J 2
(-6125 5650);
DISPLAY 0.872340 (-6125 5650);
DISPLAY INVISIBLE (-6125 5650);
FORCEPROP 1 LAST PATH I246
J 2
(-5798 5775);
DISPLAY 0.872340 (-5798 5775);
PAINT GREEN (-5798 5775);
DISPLAY INVISIBLE (-5798 5775);
FORCEADD TAP..1
R 2
(-5800 5675);
FORCEPROP 3 LASTPIN (-5750 5675) SIG_NAME M_F_CPU0_SA_DQS_DP<3>
J 0
(-5740 5685);
DISPLAY 0.659574 (-5740 5685);
PAINT MONO (-5740 5685);
DISPLAY INVISIBLE (-5740 5685);
FORCEPROP 1 LASTPIN (-5750 5675) BN 3
J 2
(-5738 5683);
DISPLAY 0.489362 (-5738 5683);
PAINT GREEN (-5738 5683);
FORCEPROP 2 LAST CDS_LIB mstr_standard
J 2
(-5800 5675);
DISPLAY 0.723404 (-5800 5675);
PAINT MONO (-5800 5675);
DISPLAY INVISIBLE (-5800 5675);
FORCEPROP 1 LAST BODY_TYPE PLUMBING
J 2
(-5800 5725);
DISPLAY 0.872340 (-5800 5725);
PAINT GREEN (-5800 5725);
DISPLAY INVISIBLE (-5800 5725);
FORCEPROP 1 LAST HDL_TAP TRUE
J 2
(-6125 5550);
DISPLAY 0.872340 (-6125 5550);
DISPLAY INVISIBLE (-6125 5550);
FORCEPROP 1 LAST PATH I247
J 2
(-5798 5675);
DISPLAY 0.872340 (-5798 5675);
PAINT GREEN (-5798 5675);
DISPLAY INVISIBLE (-5798 5675);
FORCEADD TAP..1
R 2
(-6000 5925);
FORCEPROP 3 LASTPIN (-5950 5925) SIG_NAME M_F_CPU0_SA_DQS_DN<0>
J 0
(-5940 5935);
DISPLAY 0.659574 (-5940 5935);
PAINT MONO (-5940 5935);
DISPLAY INVISIBLE (-5940 5935);
FORCEPROP 1 LASTPIN (-5950 5925) BN 0
J 2
(-5938 5933);
DISPLAY 0.489362 (-5938 5933);
PAINT GREEN (-5938 5933);
FORCEPROP 2 LAST CDS_LIB mstr_standard
J 2
(-6000 5925);
DISPLAY 0.723404 (-6000 5925);
PAINT MONO (-6000 5925);
DISPLAY INVISIBLE (-6000 5925);
FORCEPROP 1 LAST BODY_TYPE PLUMBING
J 2
(-6000 5975);
DISPLAY 0.872340 (-6000 5975);
PAINT GREEN (-6000 5975);
DISPLAY INVISIBLE (-6000 5975);
FORCEPROP 1 LAST HDL_TAP TRUE
J 2
(-6325 5800);
DISPLAY 0.872340 (-6325 5800);
DISPLAY INVISIBLE (-6325 5800);
FORCEPROP 1 LAST PATH I248
J 2
(-5998 5925);
DISPLAY 0.872340 (-5998 5925);
PAINT GREEN (-5998 5925);
DISPLAY INVISIBLE (-5998 5925);
FORCEADD TAP..1
R 2
(-6000 5825);
FORCEPROP 3 LASTPIN (-5950 5825) SIG_NAME M_F_CPU0_SA_DQS_DN<1>
J 0
(-5940 5835);
DISPLAY 0.659574 (-5940 5835);
PAINT MONO (-5940 5835);
DISPLAY INVISIBLE (-5940 5835);
FORCEPROP 1 LASTPIN (-5950 5825) BN 1
J 2
(-5938 5833);
DISPLAY 0.489362 (-5938 5833);
PAINT GREEN (-5938 5833);
FORCEPROP 2 LAST CDS_LIB mstr_standard
J 2
(-6000 5825);
DISPLAY 0.723404 (-6000 5825);
PAINT MONO (-6000 5825);
DISPLAY INVISIBLE (-6000 5825);
FORCEPROP 1 LAST BODY_TYPE PLUMBING
J 2
(-6000 5875);
DISPLAY 0.872340 (-6000 5875);
PAINT GREEN (-6000 5875);
DISPLAY INVISIBLE (-6000 5875);
FORCEPROP 1 LAST HDL_TAP TRUE
J 2
(-6325 5700);
DISPLAY 0.872340 (-6325 5700);
DISPLAY INVISIBLE (-6325 5700);
FORCEPROP 1 LAST PATH I249
J 2
(-5998 5825);
DISPLAY 0.872340 (-5998 5825);
PAINT GREEN (-5998 5825);
DISPLAY INVISIBLE (-5998 5825);
FORCEADD TAP..1
R 2
(-6000 5725);
FORCEPROP 3 LASTPIN (-5950 5725) SIG_NAME M_F_CPU0_SA_DQS_DN<2>
J 0
(-5940 5735);
DISPLAY 0.659574 (-5940 5735);
PAINT MONO (-5940 5735);
DISPLAY INVISIBLE (-5940 5735);
FORCEPROP 1 LASTPIN (-5950 5725) BN 2
J 2
(-5938 5733);
DISPLAY 0.489362 (-5938 5733);
PAINT GREEN (-5938 5733);
FORCEPROP 2 LAST CDS_LIB mstr_standard
J 2
(-6000 5725);
DISPLAY 0.723404 (-6000 5725);
PAINT MONO (-6000 5725);
DISPLAY INVISIBLE (-6000 5725);
FORCEPROP 1 LAST BODY_TYPE PLUMBING
J 2
(-6000 5775);
DISPLAY 0.872340 (-6000 5775);
PAINT GREEN (-6000 5775);
DISPLAY INVISIBLE (-6000 5775);
FORCEPROP 1 LAST HDL_TAP TRUE
J 2
(-6325 5600);
DISPLAY 0.872340 (-6325 5600);
DISPLAY INVISIBLE (-6325 5600);
FORCEPROP 1 LAST PATH I250
J 2
(-5998 5725);
DISPLAY 0.872340 (-5998 5725);
PAINT GREEN (-5998 5725);
DISPLAY INVISIBLE (-5998 5725);
FORCEADD TAP..1
R 2
(-5800 5575);
FORCEPROP 3 LASTPIN (-5750 5575) SIG_NAME M_F_CPU0_SA_DQS_DP<4>
J 0
(-5740 5585);
DISPLAY 0.659574 (-5740 5585);
PAINT MONO (-5740 5585);
DISPLAY INVISIBLE (-5740 5585);
FORCEPROP 1 LASTPIN (-5750 5575) BN 4
J 2
(-5738 5583);
DISPLAY 0.489362 (-5738 5583);
PAINT GREEN (-5738 5583);
FORCEPROP 2 LAST CDS_LIB mstr_standard
J 2
(-5800 5575);
DISPLAY 0.723404 (-5800 5575);
PAINT MONO (-5800 5575);
DISPLAY INVISIBLE (-5800 5575);
FORCEPROP 1 LAST BODY_TYPE PLUMBING
J 2
(-5800 5625);
DISPLAY 0.872340 (-5800 5625);
PAINT GREEN (-5800 5625);
DISPLAY INVISIBLE (-5800 5625);
FORCEPROP 1 LAST HDL_TAP TRUE
J 2
(-6125 5450);
DISPLAY 0.872340 (-6125 5450);
DISPLAY INVISIBLE (-6125 5450);
FORCEPROP 1 LAST PATH I251
J 2
(-5798 5575);
DISPLAY 0.872340 (-5798 5575);
PAINT GREEN (-5798 5575);
DISPLAY INVISIBLE (-5798 5575);
FORCEADD TAP..1
R 2
(-5800 5475);
FORCEPROP 3 LASTPIN (-5750 5475) SIG_NAME M_F_CPU0_SA_DQS_DP<5>
J 0
(-5740 5485);
DISPLAY 0.659574 (-5740 5485);
PAINT MONO (-5740 5485);
DISPLAY INVISIBLE (-5740 5485);
FORCEPROP 1 LASTPIN (-5750 5475) BN 5
J 2
(-5738 5483);
DISPLAY 0.489362 (-5738 5483);
PAINT GREEN (-5738 5483);
FORCEPROP 2 LAST CDS_LIB mstr_standard
J 2
(-5800 5475);
DISPLAY 0.723404 (-5800 5475);
PAINT MONO (-5800 5475);
DISPLAY INVISIBLE (-5800 5475);
FORCEPROP 1 LAST BODY_TYPE PLUMBING
J 2
(-5800 5525);
DISPLAY 0.872340 (-5800 5525);
PAINT GREEN (-5800 5525);
DISPLAY INVISIBLE (-5800 5525);
FORCEPROP 1 LAST HDL_TAP TRUE
J 2
(-6125 5350);
DISPLAY 0.872340 (-6125 5350);
DISPLAY INVISIBLE (-6125 5350);
FORCEPROP 1 LAST PATH I252
J 2
(-5798 5475);
DISPLAY 0.872340 (-5798 5475);
PAINT GREEN (-5798 5475);
DISPLAY INVISIBLE (-5798 5475);
FORCEADD TAP..1
R 2
(-5800 5375);
FORCEPROP 3 LASTPIN (-5750 5375) SIG_NAME M_F_CPU0_SA_DQS_DP<6>
J 0
(-5740 5385);
DISPLAY 0.659574 (-5740 5385);
PAINT MONO (-5740 5385);
DISPLAY INVISIBLE (-5740 5385);
FORCEPROP 1 LASTPIN (-5750 5375) BN 6
J 2
(-5738 5383);
DISPLAY 0.489362 (-5738 5383);
PAINT GREEN (-5738 5383);
FORCEPROP 2 LAST CDS_LIB mstr_standard
J 2
(-5800 5375);
DISPLAY 0.723404 (-5800 5375);
PAINT MONO (-5800 5375);
DISPLAY INVISIBLE (-5800 5375);
FORCEPROP 1 LAST BODY_TYPE PLUMBING
J 2
(-5800 5425);
DISPLAY 0.872340 (-5800 5425);
PAINT GREEN (-5800 5425);
DISPLAY INVISIBLE (-5800 5425);
FORCEPROP 1 LAST HDL_TAP TRUE
J 2
(-6125 5250);
DISPLAY 0.872340 (-6125 5250);
DISPLAY INVISIBLE (-6125 5250);
FORCEPROP 1 LAST PATH I253
J 2
(-5798 5375);
DISPLAY 0.872340 (-5798 5375);
PAINT GREEN (-5798 5375);
DISPLAY INVISIBLE (-5798 5375);
FORCEADD TAP..1
R 2
(-5800 5275);
FORCEPROP 3 LASTPIN (-5750 5275) SIG_NAME M_F_CPU0_SA_DQS_DP<7>
J 0
(-5740 5285);
DISPLAY 0.659574 (-5740 5285);
PAINT MONO (-5740 5285);
DISPLAY INVISIBLE (-5740 5285);
FORCEPROP 1 LASTPIN (-5750 5275) BN 7
J 2
(-5738 5283);
DISPLAY 0.489362 (-5738 5283);
PAINT GREEN (-5738 5283);
FORCEPROP 2 LAST CDS_LIB mstr_standard
J 2
(-5800 5275);
DISPLAY 0.723404 (-5800 5275);
PAINT MONO (-5800 5275);
DISPLAY INVISIBLE (-5800 5275);
FORCEPROP 1 LAST BODY_TYPE PLUMBING
J 2
(-5800 5325);
DISPLAY 0.872340 (-5800 5325);
PAINT GREEN (-5800 5325);
DISPLAY INVISIBLE (-5800 5325);
FORCEPROP 1 LAST HDL_TAP TRUE
J 2
(-6125 5150);
DISPLAY 0.872340 (-6125 5150);
DISPLAY INVISIBLE (-6125 5150);
FORCEPROP 1 LAST PATH I254
J 2
(-5798 5275);
DISPLAY 0.872340 (-5798 5275);
PAINT GREEN (-5798 5275);
DISPLAY INVISIBLE (-5798 5275);
FORCEADD TAP..1
R 2
(-5800 5175);
FORCEPROP 3 LASTPIN (-5750 5175) SIG_NAME M_F_CPU0_SA_DQS_DP<8>
J 0
(-5740 5185);
DISPLAY 0.659574 (-5740 5185);
PAINT MONO (-5740 5185);
DISPLAY INVISIBLE (-5740 5185);
FORCEPROP 1 LASTPIN (-5750 5175) BN 8
J 2
(-5738 5183);
DISPLAY 0.489362 (-5738 5183);
PAINT GREEN (-5738 5183);
FORCEPROP 2 LAST CDS_LIB mstr_standard
J 2
(-5800 5175);
DISPLAY 0.723404 (-5800 5175);
PAINT MONO (-5800 5175);
DISPLAY INVISIBLE (-5800 5175);
FORCEPROP 1 LAST BODY_TYPE PLUMBING
J 2
(-5800 5225);
DISPLAY 0.872340 (-5800 5225);
PAINT GREEN (-5800 5225);
DISPLAY INVISIBLE (-5800 5225);
FORCEPROP 1 LAST HDL_TAP TRUE
J 2
(-6125 5050);
DISPLAY 0.872340 (-6125 5050);
DISPLAY INVISIBLE (-6125 5050);
FORCEPROP 1 LAST PATH I255
J 2
(-5798 5175);
DISPLAY 0.872340 (-5798 5175);
PAINT GREEN (-5798 5175);
DISPLAY INVISIBLE (-5798 5175);
FORCEADD TAP..1
R 2
(-6000 5625);
FORCEPROP 3 LASTPIN (-5950 5625) SIG_NAME M_F_CPU0_SA_DQS_DN<3>
J 0
(-5940 5635);
DISPLAY 0.659574 (-5940 5635);
PAINT MONO (-5940 5635);
DISPLAY INVISIBLE (-5940 5635);
FORCEPROP 1 LASTPIN (-5950 5625) BN 3
J 2
(-5938 5633);
DISPLAY 0.489362 (-5938 5633);
PAINT GREEN (-5938 5633);
FORCEPROP 2 LAST CDS_LIB mstr_standard
J 2
(-6000 5625);
DISPLAY 0.723404 (-6000 5625);
PAINT MONO (-6000 5625);
DISPLAY INVISIBLE (-6000 5625);
FORCEPROP 1 LAST BODY_TYPE PLUMBING
J 2
(-6000 5675);
DISPLAY 0.872340 (-6000 5675);
PAINT GREEN (-6000 5675);
DISPLAY INVISIBLE (-6000 5675);
FORCEPROP 1 LAST HDL_TAP TRUE
J 2
(-6325 5500);
DISPLAY 0.872340 (-6325 5500);
DISPLAY INVISIBLE (-6325 5500);
FORCEPROP 1 LAST PATH I256
J 2
(-5998 5625);
DISPLAY 0.872340 (-5998 5625);
PAINT GREEN (-5998 5625);
DISPLAY INVISIBLE (-5998 5625);
FORCEADD TAP..1
R 2
(-6000 5525);
FORCEPROP 3 LASTPIN (-5950 5525) SIG_NAME M_F_CPU0_SA_DQS_DN<4>
J 0
(-5940 5535);
DISPLAY 0.659574 (-5940 5535);
PAINT MONO (-5940 5535);
DISPLAY INVISIBLE (-5940 5535);
FORCEPROP 1 LASTPIN (-5950 5525) BN 4
J 2
(-5938 5533);
DISPLAY 0.489362 (-5938 5533);
PAINT GREEN (-5938 5533);
FORCEPROP 2 LAST CDS_LIB mstr_standard
J 2
(-6000 5525);
DISPLAY 0.723404 (-6000 5525);
PAINT MONO (-6000 5525);
DISPLAY INVISIBLE (-6000 5525);
FORCEPROP 1 LAST BODY_TYPE PLUMBING
J 2
(-6000 5575);
DISPLAY 0.872340 (-6000 5575);
PAINT GREEN (-6000 5575);
DISPLAY INVISIBLE (-6000 5575);
FORCEPROP 1 LAST HDL_TAP TRUE
J 2
(-6325 5400);
DISPLAY 0.872340 (-6325 5400);
DISPLAY INVISIBLE (-6325 5400);
FORCEPROP 1 LAST PATH I257
J 2
(-5998 5525);
DISPLAY 0.872340 (-5998 5525);
PAINT GREEN (-5998 5525);
DISPLAY INVISIBLE (-5998 5525);
FORCEADD TAP..1
R 2
(-6000 5425);
FORCEPROP 3 LASTPIN (-5950 5425) SIG_NAME M_F_CPU0_SA_DQS_DN<5>
J 0
(-5940 5435);
DISPLAY 0.659574 (-5940 5435);
PAINT MONO (-5940 5435);
DISPLAY INVISIBLE (-5940 5435);
FORCEPROP 1 LASTPIN (-5950 5425) BN 5
J 2
(-5938 5433);
DISPLAY 0.489362 (-5938 5433);
PAINT GREEN (-5938 5433);
FORCEPROP 2 LAST CDS_LIB mstr_standard
J 2
(-6000 5425);
DISPLAY 0.723404 (-6000 5425);
PAINT MONO (-6000 5425);
DISPLAY INVISIBLE (-6000 5425);
FORCEPROP 1 LAST BODY_TYPE PLUMBING
J 2
(-6000 5475);
DISPLAY 0.872340 (-6000 5475);
PAINT GREEN (-6000 5475);
DISPLAY INVISIBLE (-6000 5475);
FORCEPROP 1 LAST HDL_TAP TRUE
J 2
(-6325 5300);
DISPLAY 0.872340 (-6325 5300);
DISPLAY INVISIBLE (-6325 5300);
FORCEPROP 1 LAST PATH I258
J 2
(-5998 5425);
DISPLAY 0.872340 (-5998 5425);
PAINT GREEN (-5998 5425);
DISPLAY INVISIBLE (-5998 5425);
FORCEADD TAP..1
R 2
(-6000 5325);
FORCEPROP 3 LASTPIN (-5950 5325) SIG_NAME M_F_CPU0_SA_DQS_DN<6>
J 0
(-5940 5335);
DISPLAY 0.659574 (-5940 5335);
PAINT MONO (-5940 5335);
DISPLAY INVISIBLE (-5940 5335);
FORCEPROP 1 LASTPIN (-5950 5325) BN 6
J 2
(-5938 5333);
DISPLAY 0.489362 (-5938 5333);
PAINT GREEN (-5938 5333);
FORCEPROP 2 LAST CDS_LIB mstr_standard
J 2
(-6000 5325);
DISPLAY 0.723404 (-6000 5325);
PAINT MONO (-6000 5325);
DISPLAY INVISIBLE (-6000 5325);
FORCEPROP 1 LAST BODY_TYPE PLUMBING
J 2
(-6000 5375);
DISPLAY 0.872340 (-6000 5375);
PAINT GREEN (-6000 5375);
DISPLAY INVISIBLE (-6000 5375);
FORCEPROP 1 LAST HDL_TAP TRUE
J 2
(-6325 5200);
DISPLAY 0.872340 (-6325 5200);
DISPLAY INVISIBLE (-6325 5200);
FORCEPROP 1 LAST PATH I259
J 2
(-5998 5325);
DISPLAY 0.872340 (-5998 5325);
PAINT GREEN (-5998 5325);
DISPLAY INVISIBLE (-5998 5325);
FORCEADD TAP..1
R 2
(-6000 5125);
FORCEPROP 3 LASTPIN (-5950 5125) SIG_NAME M_F_CPU0_SA_DQS_DN<8>
J 0
(-5940 5135);
DISPLAY 0.659574 (-5940 5135);
PAINT MONO (-5940 5135);
DISPLAY INVISIBLE (-5940 5135);
FORCEPROP 1 LASTPIN (-5950 5125) BN 8
J 2
(-5938 5133);
DISPLAY 0.489362 (-5938 5133);
PAINT GREEN (-5938 5133);
FORCEPROP 2 LAST CDS_LIB mstr_standard
J 2
(-6000 5125);
DISPLAY 0.723404 (-6000 5125);
PAINT MONO (-6000 5125);
DISPLAY INVISIBLE (-6000 5125);
FORCEPROP 1 LAST BODY_TYPE PLUMBING
J 2
(-6000 5175);
DISPLAY 0.872340 (-6000 5175);
PAINT GREEN (-6000 5175);
DISPLAY INVISIBLE (-6000 5175);
FORCEPROP 1 LAST HDL_TAP TRUE
J 2
(-6325 5000);
DISPLAY 0.872340 (-6325 5000);
DISPLAY INVISIBLE (-6325 5000);
FORCEPROP 1 LAST PATH I260
J 2
(-5998 5125);
DISPLAY 0.872340 (-5998 5125);
PAINT GREEN (-5998 5125);
DISPLAY INVISIBLE (-5998 5125);
FORCEADD TAP..1
R 2
(-6000 5225);
FORCEPROP 3 LASTPIN (-5950 5225) SIG_NAME M_F_CPU0_SA_DQS_DN<7>
J 0
(-5940 5235);
DISPLAY 0.659574 (-5940 5235);
PAINT MONO (-5940 5235);
DISPLAY INVISIBLE (-5940 5235);
FORCEPROP 1 LASTPIN (-5950 5225) BN 7
J 2
(-5938 5233);
DISPLAY 0.489362 (-5938 5233);
PAINT GREEN (-5938 5233);
FORCEPROP 2 LAST CDS_LIB mstr_standard
J 2
(-6000 5225);
DISPLAY 0.723404 (-6000 5225);
PAINT MONO (-6000 5225);
DISPLAY INVISIBLE (-6000 5225);
FORCEPROP 1 LAST BODY_TYPE PLUMBING
J 2
(-6000 5275);
DISPLAY 0.872340 (-6000 5275);
PAINT GREEN (-6000 5275);
DISPLAY INVISIBLE (-6000 5275);
FORCEPROP 1 LAST HDL_TAP TRUE
J 2
(-6325 5100);
DISPLAY 0.872340 (-6325 5100);
DISPLAY INVISIBLE (-6325 5100);
FORCEPROP 1 LAST PATH I261
J 2
(-5998 5225);
DISPLAY 0.872340 (-5998 5225);
PAINT GREEN (-5998 5225);
DISPLAY INVISIBLE (-5998 5225);
FORCEADD TAP..1
R 2
(-5800 5075);
FORCEPROP 3 LASTPIN (-5750 5075) SIG_NAME M_F_CPU0_SA_DQS_DP<9>
J 0
(-5740 5085);
DISPLAY 0.659574 (-5740 5085);
PAINT MONO (-5740 5085);
DISPLAY INVISIBLE (-5740 5085);
FORCEPROP 1 LASTPIN (-5750 5075) BN 9
J 2
(-5738 5083);
DISPLAY 0.489362 (-5738 5083);
PAINT GREEN (-5738 5083);
FORCEPROP 2 LAST CDS_LIB mstr_standard
J 2
(-5800 5075);
DISPLAY 0.723404 (-5800 5075);
PAINT MONO (-5800 5075);
DISPLAY INVISIBLE (-5800 5075);
FORCEPROP 1 LAST BODY_TYPE PLUMBING
J 2
(-5800 5125);
DISPLAY 0.872340 (-5800 5125);
PAINT GREEN (-5800 5125);
DISPLAY INVISIBLE (-5800 5125);
FORCEPROP 1 LAST HDL_TAP TRUE
J 2
(-6125 4950);
DISPLAY 0.872340 (-6125 4950);
DISPLAY INVISIBLE (-6125 4950);
FORCEPROP 1 LAST PATH I262
J 2
(-5798 5075);
DISPLAY 0.872340 (-5798 5075);
PAINT GREEN (-5798 5075);
DISPLAY INVISIBLE (-5798 5075);
FORCEADD TAP..1
R 2
(-5800 4925);
FORCEPROP 3 LASTPIN (-5750 4925) SIG_NAME M_F_CPU0_SB_DQS_DP<0>
J 0
(-5740 4935);
DISPLAY 0.659574 (-5740 4935);
PAINT MONO (-5740 4935);
DISPLAY INVISIBLE (-5740 4935);
FORCEPROP 1 LASTPIN (-5750 4925) BN 0
J 2
(-5738 4933);
DISPLAY 0.489362 (-5738 4933);
PAINT GREEN (-5738 4933);
FORCEPROP 2 LAST CDS_LIB mstr_standard
J 2
(-5800 4925);
DISPLAY 0.723404 (-5800 4925);
PAINT MONO (-5800 4925);
DISPLAY INVISIBLE (-5800 4925);
FORCEPROP 1 LAST BODY_TYPE PLUMBING
J 2
(-5800 4975);
DISPLAY 0.872340 (-5800 4975);
PAINT GREEN (-5800 4975);
DISPLAY INVISIBLE (-5800 4975);
FORCEPROP 1 LAST HDL_TAP TRUE
J 2
(-6125 4800);
DISPLAY 0.872340 (-6125 4800);
DISPLAY INVISIBLE (-6125 4800);
FORCEPROP 1 LAST PATH I263
J 2
(-5798 4925);
DISPLAY 0.872340 (-5798 4925);
PAINT GREEN (-5798 4925);
DISPLAY INVISIBLE (-5798 4925);
FORCEADD TAP..1
R 2
(-5800 4825);
FORCEPROP 3 LASTPIN (-5750 4825) SIG_NAME M_F_CPU0_SB_DQS_DP<1>
J 0
(-5740 4835);
DISPLAY 0.659574 (-5740 4835);
PAINT MONO (-5740 4835);
DISPLAY INVISIBLE (-5740 4835);
FORCEPROP 1 LASTPIN (-5750 4825) BN 1
J 2
(-5738 4833);
DISPLAY 0.489362 (-5738 4833);
PAINT GREEN (-5738 4833);
FORCEPROP 2 LAST CDS_LIB mstr_standard
J 2
(-5800 4825);
DISPLAY 0.723404 (-5800 4825);
PAINT MONO (-5800 4825);
DISPLAY INVISIBLE (-5800 4825);
FORCEPROP 1 LAST BODY_TYPE PLUMBING
J 2
(-5800 4875);
DISPLAY 0.872340 (-5800 4875);
PAINT GREEN (-5800 4875);
DISPLAY INVISIBLE (-5800 4875);
FORCEPROP 1 LAST HDL_TAP TRUE
J 2
(-6125 4700);
DISPLAY 0.872340 (-6125 4700);
DISPLAY INVISIBLE (-6125 4700);
FORCEPROP 1 LAST PATH I264
J 2
(-5798 4825);
DISPLAY 0.872340 (-5798 4825);
PAINT GREEN (-5798 4825);
DISPLAY INVISIBLE (-5798 4825);
FORCEADD TAP..1
R 2
(-5800 4725);
FORCEPROP 3 LASTPIN (-5750 4725) SIG_NAME M_F_CPU0_SB_DQS_DP<2>
J 0
(-5740 4735);
DISPLAY 0.659574 (-5740 4735);
PAINT MONO (-5740 4735);
DISPLAY INVISIBLE (-5740 4735);
FORCEPROP 1 LASTPIN (-5750 4725) BN 2
J 2
(-5738 4733);
DISPLAY 0.489362 (-5738 4733);
PAINT GREEN (-5738 4733);
FORCEPROP 2 LAST CDS_LIB mstr_standard
J 2
(-5800 4725);
DISPLAY 0.723404 (-5800 4725);
PAINT MONO (-5800 4725);
DISPLAY INVISIBLE (-5800 4725);
FORCEPROP 1 LAST BODY_TYPE PLUMBING
J 2
(-5800 4775);
DISPLAY 0.872340 (-5800 4775);
PAINT GREEN (-5800 4775);
DISPLAY INVISIBLE (-5800 4775);
FORCEPROP 1 LAST HDL_TAP TRUE
J 2
(-6125 4600);
DISPLAY 0.872340 (-6125 4600);
DISPLAY INVISIBLE (-6125 4600);
FORCEPROP 1 LAST PATH I265
J 2
(-5798 4725);
DISPLAY 0.872340 (-5798 4725);
PAINT GREEN (-5798 4725);
DISPLAY INVISIBLE (-5798 4725);
FORCEADD TAP..1
R 2
(-5800 4625);
FORCEPROP 3 LASTPIN (-5750 4625) SIG_NAME M_F_CPU0_SB_DQS_DP<3>
J 0
(-5740 4635);
DISPLAY 0.659574 (-5740 4635);
PAINT MONO (-5740 4635);
DISPLAY INVISIBLE (-5740 4635);
FORCEPROP 1 LASTPIN (-5750 4625) BN 3
J 2
(-5738 4633);
DISPLAY 0.489362 (-5738 4633);
PAINT GREEN (-5738 4633);
FORCEPROP 2 LAST CDS_LIB mstr_standard
J 2
(-5800 4625);
DISPLAY 0.723404 (-5800 4625);
PAINT MONO (-5800 4625);
DISPLAY INVISIBLE (-5800 4625);
FORCEPROP 1 LAST BODY_TYPE PLUMBING
J 2
(-5800 4675);
DISPLAY 0.872340 (-5800 4675);
PAINT GREEN (-5800 4675);
DISPLAY INVISIBLE (-5800 4675);
FORCEPROP 1 LAST HDL_TAP TRUE
J 2
(-6125 4500);
DISPLAY 0.872340 (-6125 4500);
DISPLAY INVISIBLE (-6125 4500);
FORCEPROP 1 LAST PATH I266
J 2
(-5798 4625);
DISPLAY 0.872340 (-5798 4625);
PAINT GREEN (-5798 4625);
DISPLAY INVISIBLE (-5798 4625);
FORCEADD TAP..1
R 2
(-6000 5025);
FORCEPROP 3 LASTPIN (-5950 5025) SIG_NAME M_F_CPU0_SA_DQS_DN<9>
J 0
(-5940 5035);
DISPLAY 0.659574 (-5940 5035);
PAINT MONO (-5940 5035);
DISPLAY INVISIBLE (-5940 5035);
FORCEPROP 1 LASTPIN (-5950 5025) BN 9
J 2
(-5938 5033);
DISPLAY 0.489362 (-5938 5033);
PAINT GREEN (-5938 5033);
FORCEPROP 2 LAST CDS_LIB mstr_standard
J 2
(-6000 5025);
DISPLAY 0.723404 (-6000 5025);
PAINT MONO (-6000 5025);
DISPLAY INVISIBLE (-6000 5025);
FORCEPROP 1 LAST BODY_TYPE PLUMBING
J 2
(-6000 5075);
DISPLAY 0.872340 (-6000 5075);
PAINT GREEN (-6000 5075);
DISPLAY INVISIBLE (-6000 5075);
FORCEPROP 1 LAST HDL_TAP TRUE
J 2
(-6325 4900);
DISPLAY 0.872340 (-6325 4900);
DISPLAY INVISIBLE (-6325 4900);
FORCEPROP 1 LAST PATH I267
J 2
(-5998 5025);
DISPLAY 0.872340 (-5998 5025);
PAINT GREEN (-5998 5025);
DISPLAY INVISIBLE (-5998 5025);
FORCEADD TAP..1
R 2
(-6000 4875);
FORCEPROP 3 LASTPIN (-5950 4875) SIG_NAME M_F_CPU0_SB_DQS_DN<0>
J 0
(-5940 4885);
DISPLAY 0.659574 (-5940 4885);
PAINT MONO (-5940 4885);
DISPLAY INVISIBLE (-5940 4885);
FORCEPROP 1 LASTPIN (-5950 4875) BN 0
J 2
(-5938 4883);
DISPLAY 0.489362 (-5938 4883);
PAINT GREEN (-5938 4883);
FORCEPROP 2 LAST CDS_LIB mstr_standard
J 2
(-6000 4875);
DISPLAY 0.723404 (-6000 4875);
PAINT MONO (-6000 4875);
DISPLAY INVISIBLE (-6000 4875);
FORCEPROP 1 LAST BODY_TYPE PLUMBING
J 2
(-6000 4925);
DISPLAY 0.872340 (-6000 4925);
PAINT GREEN (-6000 4925);
DISPLAY INVISIBLE (-6000 4925);
FORCEPROP 1 LAST HDL_TAP TRUE
J 2
(-6325 4750);
DISPLAY 0.872340 (-6325 4750);
DISPLAY INVISIBLE (-6325 4750);
FORCEPROP 1 LAST PATH I268
J 2
(-5998 4875);
DISPLAY 0.872340 (-5998 4875);
PAINT GREEN (-5998 4875);
DISPLAY INVISIBLE (-5998 4875);
FORCEADD TAP..1
R 2
(-6000 4775);
FORCEPROP 3 LASTPIN (-5950 4775) SIG_NAME M_F_CPU0_SB_DQS_DN<1>
J 0
(-5940 4785);
DISPLAY 0.659574 (-5940 4785);
PAINT MONO (-5940 4785);
DISPLAY INVISIBLE (-5940 4785);
FORCEPROP 1 LASTPIN (-5950 4775) BN 1
J 2
(-5938 4783);
DISPLAY 0.489362 (-5938 4783);
PAINT GREEN (-5938 4783);
FORCEPROP 2 LAST CDS_LIB mstr_standard
J 2
(-6000 4775);
DISPLAY 0.723404 (-6000 4775);
PAINT MONO (-6000 4775);
DISPLAY INVISIBLE (-6000 4775);
FORCEPROP 1 LAST BODY_TYPE PLUMBING
J 2
(-6000 4825);
DISPLAY 0.872340 (-6000 4825);
PAINT GREEN (-6000 4825);
DISPLAY INVISIBLE (-6000 4825);
FORCEPROP 1 LAST HDL_TAP TRUE
J 2
(-6325 4650);
DISPLAY 0.872340 (-6325 4650);
DISPLAY INVISIBLE (-6325 4650);
FORCEPROP 1 LAST PATH I269
J 2
(-5998 4775);
DISPLAY 0.872340 (-5998 4775);
PAINT GREEN (-5998 4775);
DISPLAY INVISIBLE (-5998 4775);
FORCEADD TAP..1
R 2
(-6000 4675);
FORCEPROP 3 LASTPIN (-5950 4675) SIG_NAME M_F_CPU0_SB_DQS_DN<2>
J 0
(-5940 4685);
DISPLAY 0.659574 (-5940 4685);
PAINT MONO (-5940 4685);
DISPLAY INVISIBLE (-5940 4685);
FORCEPROP 1 LASTPIN (-5950 4675) BN 2
J 2
(-5938 4683);
DISPLAY 0.489362 (-5938 4683);
PAINT GREEN (-5938 4683);
FORCEPROP 2 LAST CDS_LIB mstr_standard
J 2
(-6000 4675);
DISPLAY 0.723404 (-6000 4675);
PAINT MONO (-6000 4675);
DISPLAY INVISIBLE (-6000 4675);
FORCEPROP 1 LAST BODY_TYPE PLUMBING
J 2
(-6000 4725);
DISPLAY 0.872340 (-6000 4725);
PAINT GREEN (-6000 4725);
DISPLAY INVISIBLE (-6000 4725);
FORCEPROP 1 LAST HDL_TAP TRUE
J 2
(-6325 4550);
DISPLAY 0.872340 (-6325 4550);
DISPLAY INVISIBLE (-6325 4550);
FORCEPROP 1 LAST PATH I270
J 2
(-5998 4675);
DISPLAY 0.872340 (-5998 4675);
PAINT GREEN (-5998 4675);
DISPLAY INVISIBLE (-5998 4675);
FORCEADD TAP..1
R 2
(-5800 4525);
FORCEPROP 3 LASTPIN (-5750 4525) SIG_NAME M_F_CPU0_SB_DQS_DP<4>
J 0
(-5740 4535);
DISPLAY 0.659574 (-5740 4535);
PAINT MONO (-5740 4535);
DISPLAY INVISIBLE (-5740 4535);
FORCEPROP 1 LASTPIN (-5750 4525) BN 4
J 2
(-5738 4533);
DISPLAY 0.489362 (-5738 4533);
PAINT GREEN (-5738 4533);
FORCEPROP 2 LAST CDS_LIB mstr_standard
J 2
(-5800 4525);
DISPLAY 0.723404 (-5800 4525);
PAINT MONO (-5800 4525);
DISPLAY INVISIBLE (-5800 4525);
FORCEPROP 1 LAST BODY_TYPE PLUMBING
J 2
(-5800 4575);
DISPLAY 0.872340 (-5800 4575);
PAINT GREEN (-5800 4575);
DISPLAY INVISIBLE (-5800 4575);
FORCEPROP 1 LAST HDL_TAP TRUE
J 2
(-6125 4400);
DISPLAY 0.872340 (-6125 4400);
DISPLAY INVISIBLE (-6125 4400);
FORCEPROP 1 LAST PATH I271
J 2
(-5798 4525);
DISPLAY 0.872340 (-5798 4525);
PAINT GREEN (-5798 4525);
DISPLAY INVISIBLE (-5798 4525);
FORCEADD TAP..1
R 2
(-5800 4425);
FORCEPROP 3 LASTPIN (-5750 4425) SIG_NAME M_F_CPU0_SB_DQS_DP<5>
J 0
(-5740 4435);
DISPLAY 0.659574 (-5740 4435);
PAINT MONO (-5740 4435);
DISPLAY INVISIBLE (-5740 4435);
FORCEPROP 1 LASTPIN (-5750 4425) BN 5
J 2
(-5738 4433);
DISPLAY 0.489362 (-5738 4433);
PAINT GREEN (-5738 4433);
FORCEPROP 2 LAST CDS_LIB mstr_standard
J 2
(-5800 4425);
DISPLAY 0.723404 (-5800 4425);
PAINT MONO (-5800 4425);
DISPLAY INVISIBLE (-5800 4425);
FORCEPROP 1 LAST BODY_TYPE PLUMBING
J 2
(-5800 4475);
DISPLAY 0.872340 (-5800 4475);
PAINT GREEN (-5800 4475);
DISPLAY INVISIBLE (-5800 4475);
FORCEPROP 1 LAST HDL_TAP TRUE
J 2
(-6125 4300);
DISPLAY 0.872340 (-6125 4300);
DISPLAY INVISIBLE (-6125 4300);
FORCEPROP 1 LAST PATH I272
J 2
(-5798 4425);
DISPLAY 0.872340 (-5798 4425);
PAINT GREEN (-5798 4425);
DISPLAY INVISIBLE (-5798 4425);
FORCEADD TAP..1
R 2
(-5800 4325);
FORCEPROP 3 LASTPIN (-5750 4325) SIG_NAME M_F_CPU0_SB_DQS_DP<6>
J 0
(-5740 4335);
DISPLAY 0.659574 (-5740 4335);
PAINT MONO (-5740 4335);
DISPLAY INVISIBLE (-5740 4335);
FORCEPROP 1 LASTPIN (-5750 4325) BN 6
J 2
(-5738 4333);
DISPLAY 0.489362 (-5738 4333);
PAINT GREEN (-5738 4333);
FORCEPROP 2 LAST CDS_LIB mstr_standard
J 2
(-5800 4325);
DISPLAY 0.723404 (-5800 4325);
PAINT MONO (-5800 4325);
DISPLAY INVISIBLE (-5800 4325);
FORCEPROP 1 LAST BODY_TYPE PLUMBING
J 2
(-5800 4375);
DISPLAY 0.872340 (-5800 4375);
PAINT GREEN (-5800 4375);
DISPLAY INVISIBLE (-5800 4375);
FORCEPROP 1 LAST HDL_TAP TRUE
J 2
(-6125 4200);
DISPLAY 0.872340 (-6125 4200);
DISPLAY INVISIBLE (-6125 4200);
FORCEPROP 1 LAST PATH I273
J 2
(-5798 4325);
DISPLAY 0.872340 (-5798 4325);
PAINT GREEN (-5798 4325);
DISPLAY INVISIBLE (-5798 4325);
FORCEADD TAP..1
R 2
(-5800 4225);
FORCEPROP 3 LASTPIN (-5750 4225) SIG_NAME M_F_CPU0_SB_DQS_DP<7>
J 0
(-5740 4235);
DISPLAY 0.659574 (-5740 4235);
PAINT MONO (-5740 4235);
DISPLAY INVISIBLE (-5740 4235);
FORCEPROP 1 LASTPIN (-5750 4225) BN 7
J 2
(-5738 4233);
DISPLAY 0.489362 (-5738 4233);
PAINT GREEN (-5738 4233);
FORCEPROP 2 LAST CDS_LIB mstr_standard
J 2
(-5800 4225);
DISPLAY 0.723404 (-5800 4225);
PAINT MONO (-5800 4225);
DISPLAY INVISIBLE (-5800 4225);
FORCEPROP 1 LAST BODY_TYPE PLUMBING
J 2
(-5800 4275);
DISPLAY 0.872340 (-5800 4275);
PAINT GREEN (-5800 4275);
DISPLAY INVISIBLE (-5800 4275);
FORCEPROP 1 LAST HDL_TAP TRUE
J 2
(-6125 4100);
DISPLAY 0.872340 (-6125 4100);
DISPLAY INVISIBLE (-6125 4100);
FORCEPROP 1 LAST PATH I274
J 2
(-5798 4225);
DISPLAY 0.872340 (-5798 4225);
PAINT GREEN (-5798 4225);
DISPLAY INVISIBLE (-5798 4225);
FORCEADD TAP..1
R 2
(-5800 4125);
FORCEPROP 3 LASTPIN (-5750 4125) SIG_NAME M_F_CPU0_SB_DQS_DP<8>
J 0
(-5740 4135);
DISPLAY 0.659574 (-5740 4135);
PAINT MONO (-5740 4135);
DISPLAY INVISIBLE (-5740 4135);
FORCEPROP 1 LASTPIN (-5750 4125) BN 8
J 2
(-5738 4133);
DISPLAY 0.489362 (-5738 4133);
PAINT GREEN (-5738 4133);
FORCEPROP 2 LAST CDS_LIB mstr_standard
J 2
(-5800 4125);
DISPLAY 0.723404 (-5800 4125);
PAINT MONO (-5800 4125);
DISPLAY INVISIBLE (-5800 4125);
FORCEPROP 1 LAST BODY_TYPE PLUMBING
J 2
(-5800 4175);
DISPLAY 0.872340 (-5800 4175);
PAINT GREEN (-5800 4175);
DISPLAY INVISIBLE (-5800 4175);
FORCEPROP 1 LAST HDL_TAP TRUE
J 2
(-6125 4000);
DISPLAY 0.872340 (-6125 4000);
DISPLAY INVISIBLE (-6125 4000);
FORCEPROP 1 LAST PATH I275
J 2
(-5798 4125);
DISPLAY 0.872340 (-5798 4125);
PAINT GREEN (-5798 4125);
DISPLAY INVISIBLE (-5798 4125);
FORCEADD TAP..1
R 2
(-6000 4575);
FORCEPROP 3 LASTPIN (-5950 4575) SIG_NAME M_F_CPU0_SB_DQS_DN<3>
J 0
(-5940 4585);
DISPLAY 0.659574 (-5940 4585);
PAINT MONO (-5940 4585);
DISPLAY INVISIBLE (-5940 4585);
FORCEPROP 1 LASTPIN (-5950 4575) BN 3
J 2
(-5938 4583);
DISPLAY 0.489362 (-5938 4583);
PAINT GREEN (-5938 4583);
FORCEPROP 2 LAST CDS_LIB mstr_standard
J 2
(-6000 4575);
DISPLAY 0.723404 (-6000 4575);
PAINT MONO (-6000 4575);
DISPLAY INVISIBLE (-6000 4575);
FORCEPROP 1 LAST BODY_TYPE PLUMBING
J 2
(-6000 4625);
DISPLAY 0.872340 (-6000 4625);
PAINT GREEN (-6000 4625);
DISPLAY INVISIBLE (-6000 4625);
FORCEPROP 1 LAST HDL_TAP TRUE
J 2
(-6325 4450);
DISPLAY 0.872340 (-6325 4450);
DISPLAY INVISIBLE (-6325 4450);
FORCEPROP 1 LAST PATH I276
J 2
(-5998 4575);
DISPLAY 0.872340 (-5998 4575);
PAINT GREEN (-5998 4575);
DISPLAY INVISIBLE (-5998 4575);
FORCEADD TAP..1
R 2
(-6000 4475);
FORCEPROP 3 LASTPIN (-5950 4475) SIG_NAME M_F_CPU0_SB_DQS_DN<4>
J 0
(-5940 4485);
DISPLAY 0.659574 (-5940 4485);
PAINT MONO (-5940 4485);
DISPLAY INVISIBLE (-5940 4485);
FORCEPROP 1 LASTPIN (-5950 4475) BN 4
J 2
(-5938 4483);
DISPLAY 0.489362 (-5938 4483);
PAINT GREEN (-5938 4483);
FORCEPROP 2 LAST CDS_LIB mstr_standard
J 2
(-6000 4475);
DISPLAY 0.723404 (-6000 4475);
PAINT MONO (-6000 4475);
DISPLAY INVISIBLE (-6000 4475);
FORCEPROP 1 LAST BODY_TYPE PLUMBING
J 2
(-6000 4525);
DISPLAY 0.872340 (-6000 4525);
PAINT GREEN (-6000 4525);
DISPLAY INVISIBLE (-6000 4525);
FORCEPROP 1 LAST HDL_TAP TRUE
J 2
(-6325 4350);
DISPLAY 0.872340 (-6325 4350);
DISPLAY INVISIBLE (-6325 4350);
FORCEPROP 1 LAST PATH I277
J 2
(-5998 4475);
DISPLAY 0.872340 (-5998 4475);
PAINT GREEN (-5998 4475);
DISPLAY INVISIBLE (-5998 4475);
FORCEADD TAP..1
R 2
(-6000 4375);
FORCEPROP 3 LASTPIN (-5950 4375) SIG_NAME M_F_CPU0_SB_DQS_DN<5>
J 0
(-5940 4385);
DISPLAY 0.659574 (-5940 4385);
PAINT MONO (-5940 4385);
DISPLAY INVISIBLE (-5940 4385);
FORCEPROP 1 LASTPIN (-5950 4375) BN 5
J 2
(-5938 4383);
DISPLAY 0.489362 (-5938 4383);
PAINT GREEN (-5938 4383);
FORCEPROP 2 LAST CDS_LIB mstr_standard
J 2
(-6000 4375);
DISPLAY 0.723404 (-6000 4375);
PAINT MONO (-6000 4375);
DISPLAY INVISIBLE (-6000 4375);
FORCEPROP 1 LAST BODY_TYPE PLUMBING
J 2
(-6000 4425);
DISPLAY 0.872340 (-6000 4425);
PAINT GREEN (-6000 4425);
DISPLAY INVISIBLE (-6000 4425);
FORCEPROP 1 LAST HDL_TAP TRUE
J 2
(-6325 4250);
DISPLAY 0.872340 (-6325 4250);
DISPLAY INVISIBLE (-6325 4250);
FORCEPROP 1 LAST PATH I278
J 2
(-5998 4375);
DISPLAY 0.872340 (-5998 4375);
PAINT GREEN (-5998 4375);
DISPLAY INVISIBLE (-5998 4375);
FORCEADD TAP..1
R 2
(-6000 4275);
FORCEPROP 3 LASTPIN (-5950 4275) SIG_NAME M_F_CPU0_SB_DQS_DN<6>
J 0
(-5940 4285);
DISPLAY 0.659574 (-5940 4285);
PAINT MONO (-5940 4285);
DISPLAY INVISIBLE (-5940 4285);
FORCEPROP 1 LASTPIN (-5950 4275) BN 6
J 2
(-5938 4283);
DISPLAY 0.489362 (-5938 4283);
PAINT GREEN (-5938 4283);
FORCEPROP 2 LAST CDS_LIB mstr_standard
J 2
(-6000 4275);
DISPLAY 0.723404 (-6000 4275);
PAINT MONO (-6000 4275);
DISPLAY INVISIBLE (-6000 4275);
FORCEPROP 1 LAST BODY_TYPE PLUMBING
J 2
(-6000 4325);
DISPLAY 0.872340 (-6000 4325);
PAINT GREEN (-6000 4325);
DISPLAY INVISIBLE (-6000 4325);
FORCEPROP 1 LAST HDL_TAP TRUE
J 2
(-6325 4150);
DISPLAY 0.872340 (-6325 4150);
DISPLAY INVISIBLE (-6325 4150);
FORCEPROP 1 LAST PATH I279
J 2
(-5998 4275);
DISPLAY 0.872340 (-5998 4275);
PAINT GREEN (-5998 4275);
DISPLAY INVISIBLE (-5998 4275);
FORCEADD TAP..1
R 2
(-6000 4175);
FORCEPROP 3 LASTPIN (-5950 4175) SIG_NAME M_F_CPU0_SB_DQS_DN<7>
J 0
(-5940 4185);
DISPLAY 0.659574 (-5940 4185);
PAINT MONO (-5940 4185);
DISPLAY INVISIBLE (-5940 4185);
FORCEPROP 1 LASTPIN (-5950 4175) BN 7
J 2
(-5938 4183);
DISPLAY 0.489362 (-5938 4183);
PAINT GREEN (-5938 4183);
FORCEPROP 2 LAST CDS_LIB mstr_standard
J 2
(-6000 4175);
DISPLAY 0.723404 (-6000 4175);
PAINT MONO (-6000 4175);
DISPLAY INVISIBLE (-6000 4175);
FORCEPROP 1 LAST BODY_TYPE PLUMBING
J 2
(-6000 4225);
DISPLAY 0.872340 (-6000 4225);
PAINT GREEN (-6000 4225);
DISPLAY INVISIBLE (-6000 4225);
FORCEPROP 1 LAST HDL_TAP TRUE
J 2
(-6325 4050);
DISPLAY 0.872340 (-6325 4050);
DISPLAY INVISIBLE (-6325 4050);
FORCEPROP 1 LAST PATH I280
J 2
(-5998 4175);
DISPLAY 0.872340 (-5998 4175);
PAINT GREEN (-5998 4175);
DISPLAY INVISIBLE (-5998 4175);
FORCEADD OFFPAGE..3
R 2
(-6700 5950);
FORCEPROP 2 LAST $XR0 91 
J 0
(-6979 5950);
DISPLAY 0.638298 (-6979 5950);
PAINT MONO (-6979 5950);
FORCEPROP 2 LAST CDS_LIB standard
J 0
(-6700 5950);
DISPLAY INVISIBLE (-6700 5950);
FORCEPROP 1 LAST OFFPAGE TRUE
J 2
(-7025 5825);
DISPLAY 0.872340 (-7025 5825);
PAINT GREEN (-7025 5825);
DISPLAY INVISIBLE (-7025 5825);
FORCEPROP 1 LAST COMMENT_BODY TRUE
J 2
(-6650 5850);
DISPLAY 0.872340 (-6650 5850);
PAINT GREEN (-6650 5850);
DISPLAY INVISIBLE (-6650 5850);
FORCEPROP 2 LAST PATH I281
J 0
(-6975 6000);
DISPLAY 1.021277 (-6975 6000);
DISPLAY INVISIBLE (-6975 6000);
FORCEADD OFFPAGE..3
R 2
(-6700 6000);
FORCEPROP 2 LAST $XR0 91 
J 0
(-6979 6000);
DISPLAY 0.638298 (-6979 6000);
PAINT MONO (-6979 6000);
FORCEPROP 2 LAST CDS_LIB standard
J 0
(-6700 6000);
DISPLAY INVISIBLE (-6700 6000);
FORCEPROP 1 LAST OFFPAGE TRUE
J 2
(-7025 5875);
DISPLAY 0.872340 (-7025 5875);
PAINT GREEN (-7025 5875);
DISPLAY INVISIBLE (-7025 5875);
FORCEPROP 1 LAST COMMENT_BODY TRUE
J 2
(-6650 5900);
DISPLAY 0.872340 (-6650 5900);
PAINT GREEN (-6650 5900);
DISPLAY INVISIBLE (-6650 5900);
FORCEPROP 2 LAST PATH I282
J 0
(-6975 6050);
DISPLAY 1.021277 (-6975 6050);
DISPLAY INVISIBLE (-6975 6050);
FORCEADD OFFPAGE..3
R 2
(-6700 4900);
FORCEPROP 2 LAST $XR0 91 
J 0
(-6979 4900);
DISPLAY 0.638298 (-6979 4900);
PAINT MONO (-6979 4900);
FORCEPROP 2 LAST CDS_LIB standard
J 0
(-6700 4900);
DISPLAY INVISIBLE (-6700 4900);
FORCEPROP 1 LAST OFFPAGE TRUE
J 2
(-7025 4775);
DISPLAY 0.872340 (-7025 4775);
PAINT GREEN (-7025 4775);
DISPLAY INVISIBLE (-7025 4775);
FORCEPROP 1 LAST COMMENT_BODY TRUE
J 2
(-6650 4800);
DISPLAY 0.872340 (-6650 4800);
PAINT GREEN (-6650 4800);
DISPLAY INVISIBLE (-6650 4800);
FORCEPROP 2 LAST PATH I283
J 0
(-6975 4950);
DISPLAY 1.021277 (-6975 4950);
DISPLAY INVISIBLE (-6975 4950);
FORCEADD OFFPAGE..3
R 2
(-6700 4950);
FORCEPROP 2 LAST $XR0 91 
J 0
(-6979 4950);
DISPLAY 0.638298 (-6979 4950);
PAINT MONO (-6979 4950);
FORCEPROP 2 LAST CDS_LIB standard
J 0
(-6700 4950);
DISPLAY INVISIBLE (-6700 4950);
FORCEPROP 1 LAST OFFPAGE TRUE
J 2
(-7025 4825);
DISPLAY 0.872340 (-7025 4825);
PAINT GREEN (-7025 4825);
DISPLAY INVISIBLE (-7025 4825);
FORCEPROP 1 LAST COMMENT_BODY TRUE
J 2
(-6650 4850);
DISPLAY 0.872340 (-6650 4850);
PAINT GREEN (-6650 4850);
DISPLAY INVISIBLE (-6650 4850);
FORCEPROP 2 LAST PATH I284
J 0
(-6975 5000);
DISPLAY 1.021277 (-6975 5000);
DISPLAY INVISIBLE (-6975 5000);
FORCEADD TAP..1
R 2
(-5800 4025);
FORCEPROP 3 LASTPIN (-5750 4025) SIG_NAME M_F_CPU0_SB_DQS_DP<9>
J 0
(-5740 4035);
DISPLAY 0.659574 (-5740 4035);
PAINT MONO (-5740 4035);
DISPLAY INVISIBLE (-5740 4035);
FORCEPROP 1 LASTPIN (-5750 4025) BN 9
J 2
(-5738 4033);
DISPLAY 0.489362 (-5738 4033);
PAINT GREEN (-5738 4033);
FORCEPROP 2 LAST CDS_LIB mstr_standard
J 2
(-5800 4025);
DISPLAY 0.723404 (-5800 4025);
PAINT MONO (-5800 4025);
DISPLAY INVISIBLE (-5800 4025);
FORCEPROP 1 LAST BODY_TYPE PLUMBING
J 2
(-5800 4075);
DISPLAY 0.872340 (-5800 4075);
PAINT GREEN (-5800 4075);
DISPLAY INVISIBLE (-5800 4075);
FORCEPROP 1 LAST HDL_TAP TRUE
J 2
(-6125 3900);
DISPLAY 0.872340 (-6125 3900);
DISPLAY INVISIBLE (-6125 3900);
FORCEPROP 1 LAST PATH I285
J 2
(-5798 4025);
DISPLAY 0.872340 (-5798 4025);
PAINT GREEN (-5798 4025);
DISPLAY INVISIBLE (-5798 4025);
FORCEADD TAP..1
R 2
(-6000 3975);
FORCEPROP 3 LASTPIN (-5950 3975) SIG_NAME M_F_CPU0_SB_DQS_DN<9>
J 0
(-5940 3985);
DISPLAY 0.659574 (-5940 3985);
PAINT MONO (-5940 3985);
DISPLAY INVISIBLE (-5940 3985);
FORCEPROP 1 LASTPIN (-5950 3975) BN 9
J 2
(-5938 3983);
DISPLAY 0.489362 (-5938 3983);
PAINT GREEN (-5938 3983);
FORCEPROP 2 LAST CDS_LIB mstr_standard
J 2
(-6000 3975);
DISPLAY 0.723404 (-6000 3975);
PAINT MONO (-6000 3975);
DISPLAY INVISIBLE (-6000 3975);
FORCEPROP 1 LAST BODY_TYPE PLUMBING
J 2
(-6000 4025);
DISPLAY 0.872340 (-6000 4025);
PAINT GREEN (-6000 4025);
DISPLAY INVISIBLE (-6000 4025);
FORCEPROP 1 LAST HDL_TAP TRUE
J 2
(-6325 3850);
DISPLAY 0.872340 (-6325 3850);
DISPLAY INVISIBLE (-6325 3850);
FORCEPROP 1 LAST PATH I286
J 2
(-5998 3975);
DISPLAY 0.872340 (-5998 3975);
PAINT GREEN (-5998 3975);
DISPLAY INVISIBLE (-5998 3975);
FORCEADD TAP..1
R 2
(-6000 4075);
FORCEPROP 3 LASTPIN (-5950 4075) SIG_NAME M_F_CPU0_SB_DQS_DN<8>
J 0
(-5940 4085);
DISPLAY 0.659574 (-5940 4085);
PAINT MONO (-5940 4085);
DISPLAY INVISIBLE (-5940 4085);
FORCEPROP 1 LASTPIN (-5950 4075) BN 8
J 2
(-5938 4083);
DISPLAY 0.489362 (-5938 4083);
PAINT GREEN (-5938 4083);
FORCEPROP 2 LAST CDS_LIB mstr_standard
J 2
(-6000 4075);
DISPLAY 0.723404 (-6000 4075);
PAINT MONO (-6000 4075);
DISPLAY INVISIBLE (-6000 4075);
FORCEPROP 1 LAST BODY_TYPE PLUMBING
J 2
(-6000 4125);
DISPLAY 0.872340 (-6000 4125);
PAINT GREEN (-6000 4125);
DISPLAY INVISIBLE (-6000 4125);
FORCEPROP 1 LAST HDL_TAP TRUE
J 2
(-6325 3950);
DISPLAY 0.872340 (-6325 3950);
DISPLAY INVISIBLE (-6325 3950);
FORCEPROP 1 LAST PATH I287
J 2
(-5998 4075);
DISPLAY 0.872340 (-5998 4075);
PAINT GREEN (-5998 4075);
DISPLAY INVISIBLE (-5998 4075);
FORCEADD TAP..1
R 2
(-6000 3825);
FORCEPROP 3 LASTPIN (-5950 3825) SIG_NAME M_F_CPU0_SA_CA<0>
J 0
(-5940 3835);
DISPLAY 0.659574 (-5940 3835);
PAINT MONO (-5940 3835);
DISPLAY INVISIBLE (-5940 3835);
FORCEPROP 1 LASTPIN (-5950 3825) BN 0
J 2
(-5938 3833);
DISPLAY 0.489362 (-5938 3833);
PAINT GREEN (-5938 3833);
FORCEPROP 2 LAST CDS_LIB mstr_standard
J 0
(-6000 3825);
DISPLAY 0.723404 (-6000 3825);
PAINT MONO (-6000 3825);
DISPLAY INVISIBLE (-6000 3825);
FORCEPROP 1 LAST BODY_TYPE PLUMBING
J 2
(-6000 3875);
DISPLAY 0.872340 (-6000 3875);
PAINT GREEN (-6000 3875);
DISPLAY INVISIBLE (-6000 3875);
FORCEPROP 1 LAST HDL_TAP TRUE
J 2
(-6325 3700);
DISPLAY 0.872340 (-6325 3700);
DISPLAY INVISIBLE (-6325 3700);
FORCEPROP 1 LAST PATH I288
J 2
(-5998 3825);
DISPLAY 0.872340 (-5998 3825);
PAINT GREEN (-5998 3825);
DISPLAY INVISIBLE (-5998 3825);
FORCEADD TAP..1
R 2
(-6000 3775);
FORCEPROP 3 LASTPIN (-5950 3775) SIG_NAME M_F_CPU0_SA_CA<1>
J 0
(-5940 3785);
DISPLAY 0.659574 (-5940 3785);
PAINT MONO (-5940 3785);
DISPLAY INVISIBLE (-5940 3785);
FORCEPROP 1 LASTPIN (-5950 3775) BN 1
J 2
(-5938 3783);
DISPLAY 0.489362 (-5938 3783);
PAINT GREEN (-5938 3783);
FORCEPROP 2 LAST CDS_LIB mstr_standard
J 0
(-6000 3775);
DISPLAY 0.723404 (-6000 3775);
PAINT MONO (-6000 3775);
DISPLAY INVISIBLE (-6000 3775);
FORCEPROP 1 LAST BODY_TYPE PLUMBING
J 2
(-6000 3825);
DISPLAY 0.872340 (-6000 3825);
PAINT GREEN (-6000 3825);
DISPLAY INVISIBLE (-6000 3825);
FORCEPROP 1 LAST HDL_TAP TRUE
J 2
(-6325 3650);
DISPLAY 0.872340 (-6325 3650);
DISPLAY INVISIBLE (-6325 3650);
FORCEPROP 1 LAST PATH I289
J 2
(-5998 3775);
DISPLAY 0.872340 (-5998 3775);
PAINT GREEN (-5998 3775);
DISPLAY INVISIBLE (-5998 3775);
FORCEADD TAP..1
R 2
(-6000 3725);
FORCEPROP 3 LASTPIN (-5950 3725) SIG_NAME M_F_CPU0_SA_CA<2>
J 0
(-5940 3735);
DISPLAY 0.659574 (-5940 3735);
PAINT MONO (-5940 3735);
DISPLAY INVISIBLE (-5940 3735);
FORCEPROP 1 LASTPIN (-5950 3725) BN 2
J 2
(-5938 3733);
DISPLAY 0.489362 (-5938 3733);
PAINT GREEN (-5938 3733);
FORCEPROP 2 LAST CDS_LIB mstr_standard
J 0
(-6000 3725);
DISPLAY 0.723404 (-6000 3725);
PAINT MONO (-6000 3725);
DISPLAY INVISIBLE (-6000 3725);
FORCEPROP 1 LAST BODY_TYPE PLUMBING
J 2
(-6000 3775);
DISPLAY 0.872340 (-6000 3775);
PAINT GREEN (-6000 3775);
DISPLAY INVISIBLE (-6000 3775);
FORCEPROP 1 LAST HDL_TAP TRUE
J 2
(-6325 3600);
DISPLAY 0.872340 (-6325 3600);
DISPLAY INVISIBLE (-6325 3600);
FORCEPROP 1 LAST PATH I290
J 2
(-5998 3725);
DISPLAY 0.872340 (-5998 3725);
PAINT GREEN (-5998 3725);
DISPLAY INVISIBLE (-5998 3725);
FORCEADD TAP..1
R 2
(-6000 3675);
FORCEPROP 3 LASTPIN (-5950 3675) SIG_NAME M_F_CPU0_SA_CA<3>
J 0
(-5940 3685);
DISPLAY 0.659574 (-5940 3685);
PAINT MONO (-5940 3685);
DISPLAY INVISIBLE (-5940 3685);
FORCEPROP 1 LASTPIN (-5950 3675) BN 3
J 2
(-5938 3683);
DISPLAY 0.489362 (-5938 3683);
PAINT GREEN (-5938 3683);
FORCEPROP 2 LAST CDS_LIB mstr_standard
J 0
(-6000 3675);
DISPLAY 0.723404 (-6000 3675);
PAINT MONO (-6000 3675);
DISPLAY INVISIBLE (-6000 3675);
FORCEPROP 1 LAST BODY_TYPE PLUMBING
J 2
(-6000 3725);
DISPLAY 0.872340 (-6000 3725);
PAINT GREEN (-6000 3725);
DISPLAY INVISIBLE (-6000 3725);
FORCEPROP 1 LAST HDL_TAP TRUE
J 2
(-6325 3550);
DISPLAY 0.872340 (-6325 3550);
DISPLAY INVISIBLE (-6325 3550);
FORCEPROP 1 LAST PATH I291
J 2
(-5998 3675);
DISPLAY 0.872340 (-5998 3675);
PAINT GREEN (-5998 3675);
DISPLAY INVISIBLE (-5998 3675);
FORCEADD TAP..1
R 2
(-6000 3625);
FORCEPROP 3 LASTPIN (-5950 3625) SIG_NAME M_F_CPU0_SA_CA<4>
J 0
(-5940 3635);
DISPLAY 0.659574 (-5940 3635);
PAINT MONO (-5940 3635);
DISPLAY INVISIBLE (-5940 3635);
FORCEPROP 1 LASTPIN (-5950 3625) BN 4
J 2
(-5938 3633);
DISPLAY 0.489362 (-5938 3633);
PAINT GREEN (-5938 3633);
FORCEPROP 2 LAST CDS_LIB mstr_standard
J 0
(-6000 3625);
DISPLAY 0.723404 (-6000 3625);
PAINT MONO (-6000 3625);
DISPLAY INVISIBLE (-6000 3625);
FORCEPROP 1 LAST BODY_TYPE PLUMBING
J 2
(-6000 3675);
DISPLAY 0.872340 (-6000 3675);
PAINT GREEN (-6000 3675);
DISPLAY INVISIBLE (-6000 3675);
FORCEPROP 1 LAST HDL_TAP TRUE
J 2
(-6325 3500);
DISPLAY 0.872340 (-6325 3500);
DISPLAY INVISIBLE (-6325 3500);
FORCEPROP 1 LAST PATH I292
J 2
(-5998 3625);
DISPLAY 0.872340 (-5998 3625);
PAINT GREEN (-5998 3625);
DISPLAY INVISIBLE (-5998 3625);
FORCEADD TAP..1
R 2
(-6000 3575);
FORCEPROP 3 LASTPIN (-5950 3575) SIG_NAME M_F_CPU0_SA_CA<5>
J 0
(-5940 3585);
DISPLAY 0.659574 (-5940 3585);
PAINT MONO (-5940 3585);
DISPLAY INVISIBLE (-5940 3585);
FORCEPROP 1 LASTPIN (-5950 3575) BN 5
J 2
(-5938 3583);
DISPLAY 0.489362 (-5938 3583);
PAINT GREEN (-5938 3583);
FORCEPROP 2 LAST CDS_LIB mstr_standard
J 0
(-6000 3575);
DISPLAY 0.723404 (-6000 3575);
PAINT MONO (-6000 3575);
DISPLAY INVISIBLE (-6000 3575);
FORCEPROP 1 LAST BODY_TYPE PLUMBING
J 2
(-6000 3625);
DISPLAY 0.872340 (-6000 3625);
PAINT GREEN (-6000 3625);
DISPLAY INVISIBLE (-6000 3625);
FORCEPROP 1 LAST HDL_TAP TRUE
J 2
(-6325 3450);
DISPLAY 0.872340 (-6325 3450);
DISPLAY INVISIBLE (-6325 3450);
FORCEPROP 1 LAST PATH I293
J 2
(-5998 3575);
DISPLAY 0.872340 (-5998 3575);
PAINT GREEN (-5998 3575);
DISPLAY INVISIBLE (-5998 3575);
FORCEADD TAP..1
R 2
(-6000 3525);
FORCEPROP 3 LASTPIN (-5950 3525) SIG_NAME M_F_CPU0_SA_CA<6>
J 0
(-5940 3535);
DISPLAY 0.659574 (-5940 3535);
PAINT MONO (-5940 3535);
DISPLAY INVISIBLE (-5940 3535);
FORCEPROP 1 LASTPIN (-5950 3525) BN 6
J 2
(-5938 3533);
DISPLAY 0.489362 (-5938 3533);
PAINT GREEN (-5938 3533);
FORCEPROP 2 LAST CDS_LIB mstr_standard
J 0
(-6000 3525);
DISPLAY 0.723404 (-6000 3525);
PAINT MONO (-6000 3525);
DISPLAY INVISIBLE (-6000 3525);
FORCEPROP 1 LAST BODY_TYPE PLUMBING
J 2
(-6000 3575);
DISPLAY 0.872340 (-6000 3575);
PAINT GREEN (-6000 3575);
DISPLAY INVISIBLE (-6000 3575);
FORCEPROP 1 LAST HDL_TAP TRUE
J 2
(-6325 3400);
DISPLAY 0.872340 (-6325 3400);
DISPLAY INVISIBLE (-6325 3400);
FORCEPROP 1 LAST PATH I294
J 2
(-5998 3525);
DISPLAY 0.872340 (-5998 3525);
PAINT GREEN (-5998 3525);
DISPLAY INVISIBLE (-5998 3525);
FORCEADD TAP..1
R 2
(-6000 3425);
FORCEPROP 3 LASTPIN (-5950 3425) SIG_NAME M_F_CPU0_SB_CA<0>
J 0
(-5940 3435);
DISPLAY 0.659574 (-5940 3435);
PAINT MONO (-5940 3435);
DISPLAY INVISIBLE (-5940 3435);
FORCEPROP 1 LASTPIN (-5950 3425) BN 0
J 2
(-5938 3433);
DISPLAY 0.489362 (-5938 3433);
PAINT GREEN (-5938 3433);
FORCEPROP 2 LAST CDS_LIB mstr_standard
J 0
(-6000 3425);
DISPLAY 0.723404 (-6000 3425);
PAINT MONO (-6000 3425);
DISPLAY INVISIBLE (-6000 3425);
FORCEPROP 1 LAST BODY_TYPE PLUMBING
J 2
(-6000 3475);
DISPLAY 0.872340 (-6000 3475);
PAINT GREEN (-6000 3475);
DISPLAY INVISIBLE (-6000 3475);
FORCEPROP 1 LAST HDL_TAP TRUE
J 2
(-6325 3300);
DISPLAY 0.872340 (-6325 3300);
DISPLAY INVISIBLE (-6325 3300);
FORCEPROP 1 LAST PATH I295
J 2
(-5998 3425);
DISPLAY 0.872340 (-5998 3425);
PAINT GREEN (-5998 3425);
DISPLAY INVISIBLE (-5998 3425);
FORCEADD TAP..1
R 2
(-6000 3375);
FORCEPROP 3 LASTPIN (-5950 3375) SIG_NAME M_F_CPU0_SB_CA<1>
J 0
(-5940 3385);
DISPLAY 0.659574 (-5940 3385);
PAINT MONO (-5940 3385);
DISPLAY INVISIBLE (-5940 3385);
FORCEPROP 1 LASTPIN (-5950 3375) BN 1
J 2
(-5938 3383);
DISPLAY 0.489362 (-5938 3383);
PAINT GREEN (-5938 3383);
FORCEPROP 2 LAST CDS_LIB mstr_standard
J 0
(-6000 3375);
DISPLAY 0.723404 (-6000 3375);
PAINT MONO (-6000 3375);
DISPLAY INVISIBLE (-6000 3375);
FORCEPROP 1 LAST BODY_TYPE PLUMBING
J 2
(-6000 3425);
DISPLAY 0.872340 (-6000 3425);
PAINT GREEN (-6000 3425);
DISPLAY INVISIBLE (-6000 3425);
FORCEPROP 1 LAST HDL_TAP TRUE
J 2
(-6325 3250);
DISPLAY 0.872340 (-6325 3250);
DISPLAY INVISIBLE (-6325 3250);
FORCEPROP 1 LAST PATH I296
J 2
(-5998 3375);
DISPLAY 0.872340 (-5998 3375);
PAINT GREEN (-5998 3375);
DISPLAY INVISIBLE (-5998 3375);
FORCEADD TAP..1
R 2
(-6000 3325);
FORCEPROP 3 LASTPIN (-5950 3325) SIG_NAME M_F_CPU0_SB_CA<2>
J 0
(-5940 3335);
DISPLAY 0.659574 (-5940 3335);
PAINT MONO (-5940 3335);
DISPLAY INVISIBLE (-5940 3335);
FORCEPROP 1 LASTPIN (-5950 3325) BN 2
J 2
(-5938 3333);
DISPLAY 0.489362 (-5938 3333);
PAINT GREEN (-5938 3333);
FORCEPROP 2 LAST CDS_LIB mstr_standard
J 0
(-6000 3325);
DISPLAY 0.723404 (-6000 3325);
PAINT MONO (-6000 3325);
DISPLAY INVISIBLE (-6000 3325);
FORCEPROP 1 LAST BODY_TYPE PLUMBING
J 2
(-6000 3375);
DISPLAY 0.872340 (-6000 3375);
PAINT GREEN (-6000 3375);
DISPLAY INVISIBLE (-6000 3375);
FORCEPROP 1 LAST HDL_TAP TRUE
J 2
(-6325 3200);
DISPLAY 0.872340 (-6325 3200);
DISPLAY INVISIBLE (-6325 3200);
FORCEPROP 1 LAST PATH I297
J 2
(-5998 3325);
DISPLAY 0.872340 (-5998 3325);
PAINT GREEN (-5998 3325);
DISPLAY INVISIBLE (-5998 3325);
FORCEADD TAP..1
R 2
(-6000 3275);
FORCEPROP 3 LASTPIN (-5950 3275) SIG_NAME M_F_CPU0_SB_CA<3>
J 0
(-5940 3285);
DISPLAY 0.659574 (-5940 3285);
PAINT MONO (-5940 3285);
DISPLAY INVISIBLE (-5940 3285);
FORCEPROP 1 LASTPIN (-5950 3275) BN 3
J 2
(-5938 3283);
DISPLAY 0.489362 (-5938 3283);
PAINT GREEN (-5938 3283);
FORCEPROP 2 LAST CDS_LIB mstr_standard
J 0
(-6000 3275);
DISPLAY 0.723404 (-6000 3275);
PAINT MONO (-6000 3275);
DISPLAY INVISIBLE (-6000 3275);
FORCEPROP 1 LAST BODY_TYPE PLUMBING
J 2
(-6000 3325);
DISPLAY 0.872340 (-6000 3325);
PAINT GREEN (-6000 3325);
DISPLAY INVISIBLE (-6000 3325);
FORCEPROP 1 LAST HDL_TAP TRUE
J 2
(-6325 3150);
DISPLAY 0.872340 (-6325 3150);
DISPLAY INVISIBLE (-6325 3150);
FORCEPROP 1 LAST PATH I298
J 2
(-5998 3275);
DISPLAY 0.872340 (-5998 3275);
PAINT GREEN (-5998 3275);
DISPLAY INVISIBLE (-5998 3275);
FORCEADD TAP..1
R 2
(-6000 3225);
FORCEPROP 3 LASTPIN (-5950 3225) SIG_NAME M_F_CPU0_SB_CA<4>
J 0
(-5940 3235);
DISPLAY 0.659574 (-5940 3235);
PAINT MONO (-5940 3235);
DISPLAY INVISIBLE (-5940 3235);
FORCEPROP 1 LASTPIN (-5950 3225) BN 4
J 2
(-5938 3233);
DISPLAY 0.489362 (-5938 3233);
PAINT GREEN (-5938 3233);
FORCEPROP 2 LAST CDS_LIB mstr_standard
J 0
(-6000 3225);
DISPLAY 0.723404 (-6000 3225);
PAINT MONO (-6000 3225);
DISPLAY INVISIBLE (-6000 3225);
FORCEPROP 1 LAST BODY_TYPE PLUMBING
J 2
(-6000 3275);
DISPLAY 0.872340 (-6000 3275);
PAINT GREEN (-6000 3275);
DISPLAY INVISIBLE (-6000 3275);
FORCEPROP 1 LAST HDL_TAP TRUE
J 2
(-6325 3100);
DISPLAY 0.872340 (-6325 3100);
DISPLAY INVISIBLE (-6325 3100);
FORCEPROP 1 LAST PATH I299
J 2
(-5998 3225);
DISPLAY 0.872340 (-5998 3225);
PAINT GREEN (-5998 3225);
DISPLAY INVISIBLE (-5998 3225);
FORCEADD TAP..1
R 2
(-6000 3125);
FORCEPROP 3 LASTPIN (-5950 3125) SIG_NAME M_F_CPU0_SB_CA<6>
J 0
(-5940 3135);
DISPLAY 0.659574 (-5940 3135);
PAINT MONO (-5940 3135);
DISPLAY INVISIBLE (-5940 3135);
FORCEPROP 1 LASTPIN (-5950 3125) BN 6
J 2
(-5938 3133);
DISPLAY 0.489362 (-5938 3133);
PAINT GREEN (-5938 3133);
FORCEPROP 2 LAST CDS_LIB mstr_standard
J 0
(-6000 3125);
DISPLAY 0.723404 (-6000 3125);
PAINT MONO (-6000 3125);
DISPLAY INVISIBLE (-6000 3125);
FORCEPROP 1 LAST BODY_TYPE PLUMBING
J 2
(-6000 3175);
DISPLAY 0.872340 (-6000 3175);
PAINT GREEN (-6000 3175);
DISPLAY INVISIBLE (-6000 3175);
FORCEPROP 1 LAST HDL_TAP TRUE
J 2
(-6325 3000);
DISPLAY 0.872340 (-6325 3000);
DISPLAY INVISIBLE (-6325 3000);
FORCEPROP 1 LAST PATH I300
J 2
(-5998 3125);
DISPLAY 0.872340 (-5998 3125);
PAINT GREEN (-5998 3125);
DISPLAY INVISIBLE (-5998 3125);
FORCEADD TAP..1
R 2
(-6000 3175);
FORCEPROP 3 LASTPIN (-5950 3175) SIG_NAME M_F_CPU0_SB_CA<5>
J 0
(-5940 3185);
DISPLAY 0.659574 (-5940 3185);
PAINT MONO (-5940 3185);
DISPLAY INVISIBLE (-5940 3185);
FORCEPROP 1 LASTPIN (-5950 3175) BN 5
J 2
(-5938 3183);
DISPLAY 0.489362 (-5938 3183);
PAINT GREEN (-5938 3183);
FORCEPROP 2 LAST CDS_LIB mstr_standard
J 0
(-6000 3175);
DISPLAY 0.723404 (-6000 3175);
PAINT MONO (-6000 3175);
DISPLAY INVISIBLE (-6000 3175);
FORCEPROP 1 LAST BODY_TYPE PLUMBING
J 2
(-6000 3225);
DISPLAY 0.872340 (-6000 3225);
PAINT GREEN (-6000 3225);
DISPLAY INVISIBLE (-6000 3225);
FORCEPROP 1 LAST HDL_TAP TRUE
J 2
(-6325 3050);
DISPLAY 0.872340 (-6325 3050);
DISPLAY INVISIBLE (-6325 3050);
FORCEPROP 1 LAST PATH I301
J 2
(-5998 3175);
DISPLAY 0.872340 (-5998 3175);
PAINT GREEN (-5998 3175);
DISPLAY INVISIBLE (-5998 3175);
FORCEADD OFFPAGE..2
R 2
(-6600 3850);
FORCEPROP 2 LAST $XR0 91 
J 0
(-6854 3850);
DISPLAY 0.638298 (-6854 3850);
PAINT MONO (-6854 3850);
FORCEPROP 2 LAST CDS_LIB standard
J 0
(-6600 3850);
DISPLAY INVISIBLE (-6600 3850);
FORCEPROP 1 LAST OFFPAGE TRUE
J 2
(-6925 3725);
DISPLAY 0.872340 (-6925 3725);
PAINT GREEN (-6925 3725);
DISPLAY INVISIBLE (-6925 3725);
FORCEPROP 1 LAST COMMENT_BODY TRUE
J 2
(-6555 3755);
DISPLAY 0.872340 (-6555 3755);
PAINT GREEN (-6555 3755);
DISPLAY INVISIBLE (-6555 3755);
FORCEPROP 2 LAST PATH I302
J 0
(-6875 3900);
DISPLAY 1.021277 (-6875 3900);
DISPLAY INVISIBLE (-6875 3900);
FORCEADD OFFPAGE..2
R 2
(-6600 3450);
FORCEPROP 2 LAST $XR0 91 
J 0
(-6854 3450);
DISPLAY 0.638298 (-6854 3450);
PAINT MONO (-6854 3450);
FORCEPROP 2 LAST CDS_LIB standard
J 0
(-6600 3450);
DISPLAY INVISIBLE (-6600 3450);
FORCEPROP 1 LAST OFFPAGE TRUE
J 2
(-6925 3325);
DISPLAY 0.872340 (-6925 3325);
PAINT GREEN (-6925 3325);
DISPLAY INVISIBLE (-6925 3325);
FORCEPROP 1 LAST COMMENT_BODY TRUE
J 2
(-6555 3355);
DISPLAY 0.872340 (-6555 3355);
PAINT GREEN (-6555 3355);
DISPLAY INVISIBLE (-6555 3355);
FORCEPROP 2 LAST PATH I303
J 0
(-6875 3500);
DISPLAY 1.021277 (-6875 3500);
DISPLAY INVISIBLE (-6875 3500);
FORCEADD OFFPAGE..2
R 2
(-6600 2975);
FORCEPROP 2 LAST $XR0 91 
J 0
(-6854 2975);
DISPLAY 0.638298 (-6854 2975);
PAINT MONO (-6854 2975);
FORCEPROP 2 LAST CDS_LIB standard
J 0
(-6600 2975);
DISPLAY INVISIBLE (-6600 2975);
FORCEPROP 1 LAST OFFPAGE TRUE
J 2
(-6925 2850);
DISPLAY 0.872340 (-6925 2850);
PAINT GREEN (-6925 2850);
DISPLAY INVISIBLE (-6925 2850);
FORCEPROP 1 LAST COMMENT_BODY TRUE
J 2
(-6555 2880);
DISPLAY 0.872340 (-6555 2880);
PAINT GREEN (-6555 2880);
DISPLAY INVISIBLE (-6555 2880);
FORCEPROP 2 LAST PATH I304
J 0
(-6875 3025);
DISPLAY 1.021277 (-6875 3025);
DISPLAY INVISIBLE (-6875 3025);
FORCEADD OFFPAGE..2
R 2
(-6600 2925);
FORCEPROP 2 LAST $XR0 91 
J 0
(-6854 2925);
DISPLAY 0.638298 (-6854 2925);
PAINT MONO (-6854 2925);
FORCEPROP 2 LAST CDS_LIB standard
J 0
(-6600 2925);
DISPLAY INVISIBLE (-6600 2925);
FORCEPROP 1 LAST OFFPAGE TRUE
J 2
(-6925 2800);
DISPLAY 0.872340 (-6925 2800);
PAINT GREEN (-6925 2800);
DISPLAY INVISIBLE (-6925 2800);
FORCEPROP 1 LAST COMMENT_BODY TRUE
J 2
(-6555 2830);
DISPLAY 0.872340 (-6555 2830);
PAINT GREEN (-6555 2830);
DISPLAY INVISIBLE (-6555 2830);
FORCEPROP 2 LAST PATH I305
J 0
(-6875 2975);
DISPLAY 1.021277 (-6875 2975);
DISPLAY INVISIBLE (-6875 2975);
FORCEADD OFFPAGE..2
R 2
(-6600 2825);
FORCEPROP 2 LAST $XR0 91 
J 0
(-6854 2825);
DISPLAY 0.638298 (-6854 2825);
PAINT MONO (-6854 2825);
FORCEPROP 2 LAST CDS_LIB standard
J 0
(-6600 2825);
DISPLAY INVISIBLE (-6600 2825);
FORCEPROP 1 LAST OFFPAGE TRUE
J 2
(-6925 2700);
DISPLAY 0.872340 (-6925 2700);
PAINT GREEN (-6925 2700);
DISPLAY INVISIBLE (-6925 2700);
FORCEPROP 1 LAST COMMENT_BODY TRUE
J 2
(-6555 2730);
DISPLAY 0.872340 (-6555 2730);
PAINT GREEN (-6555 2730);
DISPLAY INVISIBLE (-6555 2730);
FORCEPROP 2 LAST PATH I306
J 0
(-6875 2875);
DISPLAY 1.021277 (-6875 2875);
DISPLAY INVISIBLE (-6875 2875);
FORCEADD OFFPAGE..2
R 2
(-6600 2775);
FORCEPROP 2 LAST $XR0 91 
J 0
(-6854 2775);
DISPLAY 0.638298 (-6854 2775);
PAINT MONO (-6854 2775);
FORCEPROP 2 LAST CDS_LIB standard
J 0
(-6600 2775);
DISPLAY INVISIBLE (-6600 2775);
FORCEPROP 1 LAST OFFPAGE TRUE
J 2
(-6925 2650);
DISPLAY 0.872340 (-6925 2650);
PAINT GREEN (-6925 2650);
DISPLAY INVISIBLE (-6925 2650);
FORCEPROP 1 LAST COMMENT_BODY TRUE
J 2
(-6555 2680);
DISPLAY 0.872340 (-6555 2680);
PAINT GREEN (-6555 2680);
DISPLAY INVISIBLE (-6555 2680);
FORCEPROP 2 LAST PATH I307
J 0
(-6875 2825);
DISPLAY 1.021277 (-6875 2825);
DISPLAY INVISIBLE (-6875 2825);
FORCEADD OFFPAGE..1
(-6600 2325);
FORCEPROP 2 LAST $XR0 91 
J 0
(-6821 2325);
DISPLAY 0.638298 (-6821 2325);
PAINT MONO (-6821 2325);
FORCEPROP 2 LAST CDS_LIB standard
J 0
(-6600 2325);
DISPLAY INVISIBLE (-6600 2325);
FORCEPROP 1 LAST OFFPAGE TRUE
J 0
(-6275 2200);
DISPLAY 0.872340 (-6275 2200);
PAINT GREEN (-6275 2200);
DISPLAY INVISIBLE (-6275 2200);
FORCEPROP 1 LAST COMMENT_BODY TRUE
J 0
(-6475 2225);
DISPLAY 0.872340 (-6475 2225);
PAINT GREEN (-6475 2225);
DISPLAY INVISIBLE (-6475 2225);
FORCEPROP 2 LAST PATH I308
J 0
(-6850 2375);
DISPLAY 1.021277 (-6850 2375);
DISPLAY INVISIBLE (-6850 2375);
FORCEADD OFFPAGE..1
(-6600 2675);
FORCEPROP 2 LAST $XR0 91 
J 0
(-6821 2675);
DISPLAY 0.638298 (-6821 2675);
PAINT MONO (-6821 2675);
FORCEPROP 2 LAST CDS_LIB standard
J 0
(-6600 2675);
DISPLAY INVISIBLE (-6600 2675);
FORCEPROP 1 LAST OFFPAGE TRUE
J 0
(-6275 2550);
DISPLAY 0.872340 (-6275 2550);
PAINT GREEN (-6275 2550);
DISPLAY INVISIBLE (-6275 2550);
FORCEPROP 1 LAST COMMENT_BODY TRUE
J 0
(-6475 2575);
DISPLAY 0.872340 (-6475 2575);
PAINT GREEN (-6475 2575);
DISPLAY INVISIBLE (-6475 2575);
FORCEPROP 2 LAST PATH I309
J 0
(-6850 2725);
DISPLAY 1.021277 (-6850 2725);
DISPLAY INVISIBLE (-6850 2725);
FORCEADD OFFPAGE..5
(-6600 2575);
FORCEPROP 2 LAST $XR0 91 
J 0
(-6854 2575);
DISPLAY 0.638298 (-6854 2575);
PAINT MONO (-6854 2575);
FORCEPROP 2 LAST CDS_LIB mstr_standard
J 0
(-6600 2575);
DISPLAY INVISIBLE (-6600 2575);
FORCEPROP 1 LAST OFFPAGE TRUE
J 0
(-6275 2450);
DISPLAY 0.872340 (-6275 2450);
PAINT GREEN (-6275 2450);
DISPLAY INVISIBLE (-6275 2450);
FORCEPROP 1 LAST COMMENT_BODY TRUE
J 0
(-6500 2500);
DISPLAY 0.872340 (-6500 2500);
PAINT GREEN (-6500 2500);
DISPLAY INVISIBLE (-6500 2500);
FORCEPROP 2 LAST PATH I310
J 0
(-6875 2625);
DISPLAY 1.021277 (-6875 2625);
DISPLAY INVISIBLE (-6875 2625);
FORCEADD OFFPAGE..2
R 2
(-6600 2475);
FORCEPROP 2 LAST $XR0 91 
J 0
(-6854 2475);
DISPLAY 0.638298 (-6854 2475);
PAINT MONO (-6854 2475);
FORCEPROP 2 LAST CDS_LIB standard
J 0
(-6600 2475);
DISPLAY INVISIBLE (-6600 2475);
FORCEPROP 1 LAST OFFPAGE TRUE
J 2
(-6925 2350);
DISPLAY 0.872340 (-6925 2350);
PAINT GREEN (-6925 2350);
DISPLAY INVISIBLE (-6925 2350);
FORCEPROP 1 LAST COMMENT_BODY TRUE
J 2
(-6555 2380);
DISPLAY 0.872340 (-6555 2380);
PAINT GREEN (-6555 2380);
DISPLAY INVISIBLE (-6555 2380);
FORCEPROP 2 LAST PATH I311
J 0
(-6875 2525);
DISPLAY 1.021277 (-6875 2525);
DISPLAY INVISIBLE (-6875 2525);
FORCEADD OFFPAGE..2
R 2
(-6600 2425);
FORCEPROP 2 LAST $XR0 91 
J 0
(-6854 2425);
DISPLAY 0.638298 (-6854 2425);
PAINT MONO (-6854 2425);
FORCEPROP 2 LAST CDS_LIB standard
J 0
(-6600 2425);
DISPLAY INVISIBLE (-6600 2425);
FORCEPROP 1 LAST OFFPAGE TRUE
J 2
(-6925 2300);
DISPLAY 0.872340 (-6925 2300);
PAINT GREEN (-6925 2300);
DISPLAY INVISIBLE (-6925 2300);
FORCEPROP 1 LAST COMMENT_BODY TRUE
J 2
(-6555 2330);
DISPLAY 0.872340 (-6555 2330);
PAINT GREEN (-6555 2330);
DISPLAY INVISIBLE (-6555 2330);
FORCEPROP 2 LAST PATH I312
J 0
(-6875 2475);
DISPLAY 1.021277 (-6875 2475);
DISPLAY INVISIBLE (-6875 2475);
FORCEADD OFFPAGE..5
(-6600 2225);
FORCEPROP 2 LAST $XR0 91 
J 0
(-6854 2225);
DISPLAY 0.638298 (-6854 2225);
PAINT MONO (-6854 2225);
FORCEPROP 2 LAST CDS_LIB standard
J 0
(-6600 2225);
DISPLAY INVISIBLE (-6600 2225);
FORCEPROP 1 LAST OFFPAGE TRUE
J 0
(-6275 2100);
DISPLAY 0.872340 (-6275 2100);
PAINT GREEN (-6275 2100);
DISPLAY INVISIBLE (-6275 2100);
FORCEPROP 1 LAST COMMENT_BODY TRUE
J 0
(-6500 2150);
DISPLAY 0.872340 (-6500 2150);
PAINT GREEN (-6500 2150);
DISPLAY INVISIBLE (-6500 2150);
FORCEPROP 2 LAST PATH I313
J 0
(-6875 2275);
DISPLAY 1.021277 (-6875 2275);
DISPLAY INVISIBLE (-6875 2275);
FORCEADD Q_RES..1
(-6925 2125);
FORCEPROP 1 LAST LOCATION R380
J 0
(-7250 2125);
DISPLAY 0.489362 (-7250 2125);
PAINT SKYBLUE (-7250 2125);
FORCEPROP 0 LAST $SEC 1
J 0
(-7100 2175);
DISPLAY 0.680851 (-7100 2175);
PAINT MONO (-7100 2175);
DISPLAY INVISIBLE (-7100 2175);
FORCEPROP 0 LAST CDS_SEC 1
J 0
(-7100 2175);
DISPLAY 1.021277 (-7100 2175);
DISPLAY INVISIBLE (-7100 2175);
FORCEPROP 1 LASTPIN (-7025 2125) $PN 1
J 0
(-7013 2137);
DISPLAY 0.489362 (-7013 2137);
PAINT MONO (-7013 2137);
FORCEPROP 1 LASTPIN (-6825 2125) $PN 2
J 0
(-6863 2137);
DISPLAY 0.489362 (-6863 2137);
PAINT MONO (-6863 2137);
FORCEPROP 1 LAST PACK_TYPE 0402LF
J 0
(-7250 2100);
DISPLAY 0.489362 (-7250 2100);
PAINT SKYBLUE (-7250 2100);
FORCEPROP 1 LAST TOLERANCE 1%
J 0
(-6650 2125);
DISPLAY 0.489362 (-6650 2125);
PAINT SKYBLUE (-6650 2125);
FORCEPROP 1 LAST VALUE 15
J 2
(-6600 2125);
DISPLAY 0.489362 (-6600 2125);
PAINT SKYBLUE (-6600 2125);
FORCEPROP 1 LAST MATERIAL CHIP
J 0
(-7050 2250);
DISPLAY 0.638298 (-7050 2250);
PAINT SKYBLUE (-7050 2250);
DISPLAY INVISIBLE (-7050 2250);
FORCEPROP 1 LAST WATTAGE 1/16W
J 2
(-6700 2250);
DISPLAY 0.638298 (-6700 2250);
PAINT SKYBLUE (-6700 2250);
DISPLAY INVISIBLE (-6700 2250);
FORCEPROP 2 LAST CDS_LIB pure_quanta
J 0
(-6925 2125);
DISPLAY INVISIBLE (-6925 2125);
FORCEPROP 1 LAST PATH I314
J 0
(-6975 2275);
DISPLAY 0.978723 (-6975 2275);
PAINT WHITE (-6975 2275);
DISPLAY INVISIBLE (-6975 2275);
FORCEPROP 1 LAST PART_NUMBER CS01502FB03
J 0
(-6800 2100);
DISPLAY 0.489362 (-6800 2100);
PAINT SKYBLUE (-6800 2100);
DISPLAY INVISIBLE (-6800 2100);
FORCEADD OFFPAGE..1
(-7800 2125);
FORCEPROP 2 LAST $XR0 91 
J 0
(-8051 2125);
DISPLAY 0.638298 (-8051 2125);
PAINT MONO (-8051 2125);
FORCEPROP 2 LAST CDS_LIB mstr_standard
J 0
(-7800 2125);
DISPLAY INVISIBLE (-7800 2125);
FORCEPROP 1 LAST OFFPAGE TRUE
J 0
(-7475 2000);
DISPLAY 0.872340 (-7475 2000);
PAINT GREEN (-7475 2000);
DISPLAY INVISIBLE (-7475 2000);
FORCEPROP 1 LAST COMMENT_BODY TRUE
J 0
(-7675 2025);
DISPLAY 0.872340 (-7675 2025);
PAINT GREEN (-7675 2025);
DISPLAY INVISIBLE (-7675 2025);
FORCEPROP 2 LAST PATH I315
J 0
(-8075 2175);
DISPLAY 1.021277 (-8075 2175);
DISPLAY INVISIBLE (-8075 2175);
FORCEADD OFFPAGE..5
(-6600 2025);
FORCEPROP 2 LAST $XR0 91 
J 0
(-6854 2025);
DISPLAY 0.638298 (-6854 2025);
PAINT MONO (-6854 2025);
FORCEPROP 2 LAST CDS_LIB standard
J 0
(-6600 2025);
DISPLAY INVISIBLE (-6600 2025);
FORCEPROP 1 LAST OFFPAGE TRUE
J 0
(-6275 1900);
DISPLAY 0.872340 (-6275 1900);
PAINT GREEN (-6275 1900);
DISPLAY INVISIBLE (-6275 1900);
FORCEPROP 1 LAST COMMENT_BODY TRUE
J 0
(-6500 1950);
DISPLAY 0.872340 (-6500 1950);
PAINT GREEN (-6500 1950);
DISPLAY INVISIBLE (-6500 1950);
FORCEPROP 2 LAST PATH I316
J 0
(-6875 2075);
DISPLAY 1.021277 (-6875 2075);
DISPLAY INVISIBLE (-6875 2075);
FORCEADD QUANTA_TITLE_BLOCK_C..1
(-100 100);
FORCEPROP 0 LAST CDS_CON_LAST_MODIFIED Thu Sep 14 16:11:49 2023
J 0
(-1985 115);
DISPLAY INVISIBLE (-1985 115);
FORCEPROP 1 LAST CUSTOM_TXT_CDS <CON_LAST_MODIFIED>
J 0
(-1985 115);
DISPLAY 0.978723 (-1985 115);
FORCEPROP 2 LAST CUSTOM_TXT_CDS <XR_PAGE_TITLE>
J 0
(-7990 5350);
DISPLAY 0.638298 (-7990 5350);
PAINT PINK (-7990 5350);
DISPLAY INVISIBLE (-7990 5350);
FORCEPROP 1 LAST CUSTOM_TXT_CDS <NAME_2>
J 0
(-3275 150);
FORCEPROP 1 LAST CUSTOM_TXT_CDS <NAME_1>
J 0
(-3275 275);
FORCEPROP 1 LAST CUSTOM_TXT_CDS <Q_NUMBER>
J 0
(-1503 203);
DISPLAY 1.212766 (-1503 203);
FORCEPROP 1 LAST CUSTOM_TXT_CDS <Q_PROJ>
J 0
(-2482 202);
DISPLAY 1.212766 (-2482 202);
FORCEPROP 1 LAST CUSTOM_TXT_CDS <Q_REV>
J 0
(-284 203);
DISPLAY 1.212766 (-284 203);
FORCEPROP 1 LAST CUSTOM_TXT_CDS <CON_PAGE_NUM> OF <CON_TOTAL_PAGES>
J 0
(-546 118);
DISPLAY 0.978723 (-546 118);
FORCEPROP 1 LAST Q_TITLE CPU0 DDR CHF
J 0
(-9400 150);
DISPLAY 2.446809 (-9400 150);
PAINT GREEN (-9400 150);
FORCEPROP 2 LAST PAGE_BORDER TRUE
J 0
(-7990 5350);
DISPLAY 0.638298 (-7990 5350);
PAINT PINK (-7990 5350);
DISPLAY INVISIBLE (-7990 5350);
FORCEPROP 2 LAST CDS_LIB pure_quanta
J 0
(-100 100);
DISPLAY INVISIBLE (-100 100);
FORCEPROP 1 LAST CDS_LMAN_SYM_OUTLINE -9475,6775,100,-125
J 0
(-100 100);
DISPLAY 0.468085 (-100 100);
PAINT GREEN (-100 100);
DISPLAY INVISIBLE (-100 100);
FORCEPROP 2 LAST CDS_XR_PAGE_TITLE CR-15 : @T6G_MB_LIB.T6G(SCH_1):PAGE15
J 0
(-7990 5350);
DISPLAY 0.638298 (-7990 5350);
PAINT PINK (-7990 5350);
DISPLAY INVISIBLE (-7990 5350);
FORCEPROP 1 LAST Q_DEPT BU9
J 1
(-3863 149);
DISPLAY 1.957447 (-3863 149);
PAINT GREEN (-3863 149);
DISPLAY INVISIBLE (-3863 149);
FORCEPROP 1 LAST COMMENT_BODY TRUE
J 0
(-88 87);
DISPLAY 0.978723 (-88 87);
PAINT GREEN (-88 87);
DISPLAY INVISIBLE (-88 87);
FORCEADD CAD_NOTE..1
(-7750 2425);
FORCEPROP 0 LAST L1 R1954 PLACE CLOSE TO CPU < 25MM
J 0
(-7900 2300);
DISPLAY 0.617021 (-7900 2300);
PAINT WHITE (-7900 2300);
FORCEPROP 2 LAST CDS_LIB pure_quanta_power
J 0
(-7750 2425);
DISPLAY INVISIBLE (-7750 2425);
FORCEPROP 1 LAST COMMENT_BODY TRUE
J 0
(-7725 2525);
DISPLAY 0.574468 (-7725 2525);
PAINT WHITE (-7725 2525);
DISPLAY INVISIBLE (-7725 2525);
WIRE 17 -1 (-3325 5650)(-3325 5550);
WIRE 17 -1 (-3325 5700)(-3325 5650);
WIRE 17 -1 (-3325 5550)(-3325 5500);
WIRE 17 -1 (-3325 5500)(-3325 5450);
WIRE 17 -1 (-3325 5750)(-3325 5700);
WIRE 17 -1 (-3325 5800)(-3325 5750);
WIRE 17 -1 (-3325 5450)(-3325 5400);
WIRE 17 -1 (-3325 5400)(-3325 5350);
WIRE 17 -1 (-3325 5850)(-3325 5800);
WIRE 17 -1 (-3325 5900)(-3325 5850);
WIRE 17 -1 (-3325 5350)(-3325 5300);
WIRE 17 -1 (-3325 5300)(-3325 5250);
WIRE 17 -1 (-3325 5950)(-3325 5900);
WIRE 17 -1 (-3325 6000)(-3325 5950);
WIRE 17 -1 (-3325 5250)(-3325 5200);
WIRE 17 -1 (-3325 5100)(-3325 5200);
WIRE 17 -1 (-3325 6000)(-2700 6000);
FORCEPROP 2 LAST SIG_NAME M_F_CPU0_SA_DQ<31:0>
J 2
(-2760 6010);
DISPLAY 0.489362 (-2760 6010);
WIRE 17 -1 (-3325 5050)(-3325 5100);
WIRE 17 -1 (-3325 5000)(-3325 5050);
WIRE 17 -1 (-3325 4950)(-3325 5000);
WIRE 17 -1 (-3325 4950)(-3325 4900);
WIRE 17 -1 (-3325 4900)(-3325 4850);
WIRE 17 -1 (-3325 4850)(-3325 4800);
WIRE 17 -1 (-3325 4800)(-3325 4750);
WIRE 17 -1 (-3325 4750)(-3325 4650);
WIRE 17 -1 (-3325 4650)(-3325 4600);
WIRE 17 -1 (-3325 4600)(-3325 4550);
WIRE 17 -1 (-3325 4550)(-3325 4500);
WIRE 17 -1 (-3325 4450)(-3325 4500);
WIRE 17 -1 (-3325 4400)(-3325 4450);
WIRE 17 -1 (-3325 4350)(-3325 4400);
WIRE 17 -1 (-3325 4300)(-3325 4350);
WIRE 17 -1 (-3325 4200)(-2700 4200);
FORCEPROP 2 LAST SIG_NAME M_F_CPU0_SB_DQ<31:0>
J 2
(-2760 4210);
DISPLAY 0.489362 (-2760 4210);
WIRE 17 -1 (-3325 4200)(-3325 4150);
WIRE 17 -1 (-3325 3150)(-3325 3200);
WIRE 17 -1 (-3325 3150)(-3325 3100);
WIRE 17 -1 (-3325 3200)(-3325 3250);
WIRE 17 -1 (-3325 3250)(-3325 3300);
WIRE 17 -1 (-3325 3100)(-3325 3050);
WIRE 17 -1 (-3325 3050)(-3325 3000);
WIRE 17 -1 (-3325 3300)(-3325 3400);
WIRE 17 -1 (-3325 3450)(-3325 3400);
WIRE 17 -1 (-3325 3000)(-3325 2950);
WIRE 17 -1 (-3325 2950)(-3325 2850);
WIRE 17 -1 (-3325 3500)(-3325 3450);
WIRE 17 -1 (-3325 3550)(-3325 3500);
WIRE 17 -1 (-3325 2850)(-3325 2800);
WIRE 17 -1 (-3325 2800)(-3325 2750);
WIRE 17 -1 (-3325 3600)(-3325 3550);
WIRE 17 -1 (-3325 3650)(-3325 3600);
WIRE 17 -1 (-3325 2750)(-3325 2700);
WIRE 17 -1 (-3325 2650)(-3325 2700);
WIRE 17 -1 (-3325 3700)(-3325 3650);
WIRE 17 -1 (-3325 3750)(-3325 3700);
WIRE 17 -1 (-3325 2600)(-3325 2650);
WIRE 17 -1 (-3325 2550)(-3325 2600);
WIRE 17 -1 (-3325 3850)(-3325 3750);
WIRE 17 -1 (-3325 3900)(-3325 3850);
WIRE 17 -1 (-3325 2500)(-3325 2550);
WIRE 17 -1 (-3325 3950)(-3325 3900);
WIRE 17 -1 (-3325 4000)(-3325 3950);
WIRE 17 -1 (-3325 4050)(-3325 4000);
WIRE 17 -1 (-3325 4100)(-3325 4050);
WIRE 17 -1 (-3325 4150)(-3325 4100);
WIRE 17 -1 (-3325 2400)(-3325 2425);
WIRE 17 -1 (-3325 2400)(-3325 2350);
WIRE 17 -1 (-3325 2425)(-2825 2425);
FORCEPROP 2 LAST SIG_NAME M_F_CPU0_SA_CB<7:0>
J 2
(-2825 2435);
DISPLAY 0.489362 (-2825 2435);
WIRE 17 -1 (-3325 2300)(-3325 2350);
WIRE 17 -1 (-3325 2300)(-3325 2250);
WIRE 17 -1 (-3325 2200)(-3325 2250);
WIRE 17 -1 (-3325 2150)(-3325 2200);
WIRE 17 -1 (-3325 2100)(-3325 2150);
WIRE 17 -1 (-3325 2050)(-3325 2100);
WIRE 17 -1 (-3325 1950)(-3325 1975);
WIRE 17 -1 (-3325 1950)(-3325 1900);
WIRE 17 -1 (-3325 1975)(-2825 1975);
FORCEPROP 2 LAST SIG_NAME M_F_CPU0_SB_CB<7:0>
J 2
(-2825 1985);
DISPLAY 0.489362 (-2825 1985);
WIRE 17 -1 (-3325 1850)(-3325 1900);
WIRE 17 -1 (-3325 1850)(-3325 1800);
WIRE 17 -1 (-3325 1750)(-3325 1800);
WIRE 17 -1 (-3325 1700)(-3325 1750);
WIRE 17 -1 (-3325 1650)(-3325 1700);
WIRE 17 -1 (-3325 1600)(-3325 1650);
WIRE 17 -1 (-5850 5300)(-5850 5200);
WIRE 17 -1 (-5850 5300)(-5850 5400);
WIRE 17 -1 (-5850 5200)(-5850 5100);
WIRE 17 -1 (-5850 5400)(-5850 5500);
WIRE 17 -1 (-5850 5500)(-5850 5600);
WIRE 17 -1 (-5850 5700)(-5850 5600);
WIRE 17 -1 (-5850 5800)(-5850 5700);
WIRE 17 -1 (-5850 5900)(-5850 5800);
WIRE 17 -1 (-5850 6000)(-5850 5900);
WIRE 17 -1 (-5850 6000)(-6650 6000);
FORCEPROP 2 LAST SIG_NAME M_F_CPU0_SA_DQS_DP<9:0>
J 2
(-6085 6010);
DISPLAY 0.489362 (-6085 6010);
WIRE 17 -1 (-6050 5950)(-6050 5850);
FORCEPROP 2 LAST SIG_NAME M_F_CPU0_SA_DQS_DN<9:0>
J 2
(-6085 5960);
DISPLAY 0.489362 (-6085 5960);
WIRE 17 -1 (-6050 5850)(-6050 5750);
WIRE 17 -1 (-6050 5750)(-6050 5650);
WIRE 17 -1 (-6050 5650)(-6050 5550);
WIRE 17 -1 (-6050 5450)(-6050 5550);
WIRE 17 -1 (-6050 5350)(-6050 5450);
WIRE 17 -1 (-6050 5250)(-6050 5350);
WIRE 17 -1 (-6050 5250)(-6050 5150);
WIRE 17 -1 (-6050 5150)(-6050 5050);
WIRE 17 -1 (-6050 4300)(-6050 4400);
WIRE 17 -1 (-6050 4200)(-6050 4300);
WIRE 17 -1 (-6050 4400)(-6050 4500);
WIRE 17 -1 (-6050 4600)(-6050 4500);
WIRE 17 -1 (-6050 4200)(-6050 4100);
WIRE 17 -1 (-6050 4100)(-6050 4000);
WIRE 17 -1 (-6050 4700)(-6050 4600);
WIRE 17 -1 (-6050 4800)(-6050 4700);
WIRE 17 -1 (-6050 4900)(-6050 4800);
FORCEPROP 2 LAST SIG_NAME M_F_CPU0_SB_DQS_DN<9:0>
J 2
(-6085 4910);
DISPLAY 0.489362 (-6085 4910);
WIRE 17 -1 (-5850 4850)(-5850 4750);
WIRE 17 -1 (-5850 4950)(-5850 4850);
WIRE 17 -1 (-5850 4750)(-5850 4650);
WIRE 17 -1 (-5850 4650)(-5850 4550);
WIRE 17 -1 (-5850 4950)(-6650 4950);
FORCEPROP 2 LAST SIG_NAME M_F_CPU0_SB_DQS_DP<9:0>
J 2
(-6085 4960);
DISPLAY 0.489362 (-6085 4960);
WIRE 17 -1 (-5850 4450)(-5850 4550);
WIRE 17 -1 (-5850 4350)(-5850 4450);
WIRE 17 -1 (-5850 4250)(-5850 4350);
WIRE 17 -1 (-5850 4250)(-5850 4150);
WIRE 17 -1 (-5850 4150)(-5850 4050);
WIRE 17 -1 (-6050 3800)(-6050 3850);
WIRE 17 -1 (-6050 3750)(-6050 3800);
WIRE 17 -1 (-6050 3850)(-6550 3850);
FORCEPROP 2 LAST SIG_NAME M_F_CPU0_SA_CA<6:0>
J 0
(-6550 3860);
DISPLAY 0.489362 (-6550 3860);
WIRE 17 -1 (-6050 3400)(-6050 3450);
WIRE 17 -1 (-6050 3350)(-6050 3400);
WIRE 17 -1 (-6050 3450)(-6550 3450);
FORCEPROP 2 LAST SIG_NAME M_F_CPU0_SB_CA<6:0>
J 0
(-6550 3460);
DISPLAY 0.489362 (-6550 3460);
WIRE 17 -1 (-6050 3700)(-6050 3750);
WIRE 17 -1 (-6050 3300)(-6050 3350);
WIRE 17 -1 (-6050 3650)(-6050 3700);
WIRE 17 -1 (-6050 3600)(-6050 3650);
WIRE 17 -1 (-6050 3550)(-6050 3600);
WIRE 17 -1 (-6050 3250)(-6050 3300);
WIRE 17 -1 (-6050 3200)(-6050 3250);
WIRE 17 -1 (-6050 3150)(-6050 3200);
WIRE 17 -1 (-6050 5950)(-6650 5950);
WIRE 17 -1 (-6050 4900)(-6650 4900);
WIRE 16 -1 (-7750 2125)(-7025 2125);
FORCEPROP 2 LAST SIG_NAME M_F_CPU0_ALERT_N
J 0
(-7710 2135);
DISPLAY 0.489362 (-7710 2135);
WIRE 16 -1 (-6825 2125)(-5450 2125);
FORCEPROP 2 LAST SIG_NAME M_F_CPU0_ALERT_R_N
J 0
(-6535 2135);
DISPLAY 0.489362 (-6535 2135);
FORCEPROP 2 LASTPROP $XRERR UNIQUE?
J 0
(-6775 2135);
DISPLAY 0.638298 (-6775 2135);
PAINT MONO (-6775 2135);
DISPLAY INVISIBLE (-6775 2135);
WIRE 16 -1 (-6550 1175)(-5450 1175);
FORCEPROP 2 LAST SIG_NAME TP_M_F_CPU0_SA_TEST39F
J 0
(-6535 1185);
DISPLAY 0.489362 (-6535 1185);
FORCEPROP 2 LASTPROP $XRERR UNIQUE?
J 0
(-6790 1175);
DISPLAY 0.638298 (-6790 1175);
PAINT MONO (-6790 1175);
DISPLAY INVISIBLE (-6790 1175);
WIRE 16 -1 (-6550 2975)(-5450 2975);
FORCEPROP 2 LAST SIG_NAME M_F_CPU0_CLK_DP<0>
J 0
(-6550 2985);
DISPLAY 0.489362 (-6550 2985);
WIRE 16 -1 (-6550 2925)(-5450 2925);
FORCEPROP 2 LAST SIG_NAME M_F_CPU0_CLK_DN<0>
J 0
(-6550 2935);
DISPLAY 0.489362 (-6550 2935);
WIRE 16 -1 (-6550 2825)(-5450 2825);
FORCEPROP 2 LAST SIG_NAME M_F_CPU0_SA_CS_N<0>
J 0
(-6550 2835);
DISPLAY 0.489362 (-6550 2835);
WIRE 16 -1 (-6550 2775)(-5450 2775);
FORCEPROP 2 LAST SIG_NAME M_F_CPU0_SA_CS_N<1>
J 0
(-6550 2785);
DISPLAY 0.489362 (-6550 2785);
WIRE 16 -1 (-6550 2325)(-5450 2325);
FORCEPROP 2 LAST SIG_NAME M_F_CPU0_SB_RSP<0>
J 0
(-6550 2335);
DISPLAY 0.489362 (-6550 2335);
WIRE 16 -1 (-6550 2675)(-5450 2675);
FORCEPROP 2 LAST SIG_NAME M_F_CPU0_SA_RSP<0>
J 0
(-6550 2685);
DISPLAY 0.489362 (-6550 2685);
WIRE 16 -1 (-6550 2575)(-5450 2575);
FORCEPROP 2 LAST SIG_NAME M_F_CPU0_SA_PAR
J 0
(-6550 2585);
DISPLAY 0.489362 (-6550 2585);
WIRE 16 -1 (-6550 2475)(-5450 2475);
FORCEPROP 2 LAST SIG_NAME M_F_CPU0_SB_CS_N<0>
J 0
(-6550 2485);
DISPLAY 0.489362 (-6550 2485);
WIRE 16 -1 (-6550 2425)(-5450 2425);
FORCEPROP 2 LAST SIG_NAME M_F_CPU0_SB_CS_N<1>
J 0
(-6550 2435);
DISPLAY 0.489362 (-6550 2435);
WIRE 16 -1 (-6550 2225)(-5450 2225);
FORCEPROP 2 LAST SIG_NAME M_F_CPU0_SB_PAR
J 0
(-6550 2235);
DISPLAY 0.489362 (-6550 2235);
WIRE 16 -1 (-6550 2025)(-5450 2025);
FORCEPROP 2 LAST SIG_NAME M_F_CPU0_RESET_N
J 0
(-6550 2035);
DISPLAY 0.489362 (-6550 2035);
WIRE 16 -1 (-5750 4025)(-5450 4025);
WIRE 16 -1 (-5950 3125)(-5450 3125);
WIRE 16 -1 (-5950 3525)(-5450 3525);
WIRE 16 -1 (-5950 3175)(-5450 3175);
WIRE 16 -1 (-5950 3575)(-5450 3575);
WIRE 16 -1 (-5950 3225)(-5450 3225);
WIRE 16 -1 (-5950 3625)(-5450 3625);
WIRE 16 -1 (-5950 3275)(-5450 3275);
WIRE 16 -1 (-5950 3675)(-5450 3675);
WIRE 16 -1 (-5950 3325)(-5450 3325);
WIRE 16 -1 (-5950 3725)(-5450 3725);
WIRE 16 -1 (-5950 3375)(-5450 3375);
WIRE 16 -1 (-5950 3775)(-5450 3775);
WIRE 16 -1 (-5950 3425)(-5450 3425);
WIRE 16 -1 (-5950 3825)(-5450 3825);
WIRE 16 -1 (-5950 3975)(-5450 3975);
WIRE 16 -1 (-5950 4075)(-5450 4075);
WIRE 16 -1 (-5750 4825)(-5450 4825);
WIRE 16 -1 (-5950 4375)(-5450 4375);
WIRE 16 -1 (-5750 4925)(-5450 4925);
WIRE 16 -1 (-5950 4475)(-5450 4475);
WIRE 16 -1 (-5950 5025)(-5450 5025);
WIRE 16 -1 (-5950 4575)(-5450 4575);
WIRE 16 -1 (-5950 4675)(-5450 4675);
WIRE 16 -1 (-5950 4775)(-5450 4775);
WIRE 16 -1 (-5950 4875)(-5450 4875);
WIRE 16 -1 (-5750 4125)(-5450 4125);
WIRE 16 -1 (-5750 4225)(-5450 4225);
WIRE 16 -1 (-5750 4325)(-5450 4325);
WIRE 16 -1 (-5750 4425)(-5450 4425);
WIRE 16 -1 (-5750 4525)(-5450 4525);
WIRE 16 -1 (-5750 5075)(-5450 5075);
WIRE 16 -1 (-5750 4625)(-5450 4625);
WIRE 16 -1 (-5950 4175)(-5450 4175);
WIRE 16 -1 (-5750 4725)(-5450 4725);
WIRE 16 -1 (-5950 4275)(-5450 4275);
WIRE 16 -1 (-5750 5275)(-5450 5275);
WIRE 16 -1 (-5750 5375)(-5450 5375);
WIRE 16 -1 (-5750 5475)(-5450 5475);
WIRE 16 -1 (-5750 5575)(-5450 5575);
WIRE 16 -1 (-5950 5125)(-5450 5125);
WIRE 16 -1 (-5750 5675)(-5450 5675);
WIRE 16 -1 (-5950 5225)(-5450 5225);
WIRE 16 -1 (-5750 5775)(-5450 5775);
WIRE 16 -1 (-5950 5325)(-5450 5325);
WIRE 16 -1 (-5750 5875)(-5450 5875);
WIRE 16 -1 (-5950 5425)(-5450 5425);
WIRE 16 -1 (-5750 5975)(-5450 5975);
WIRE 16 -1 (-5950 5525)(-5450 5525);
WIRE 16 -1 (-5950 5625)(-5450 5625);
WIRE 16 -1 (-5950 5725)(-5450 5725);
WIRE 16 -1 (-5950 5825)(-5450 5825);
WIRE 16 -1 (-5950 5925)(-5450 5925);
WIRE 16 -1 (-5750 5175)(-5450 5175);
WIRE 16 -1 (-3850 1575)(-3425 1575);
WIRE 16 -1 (-3850 1625)(-3425 1625);
WIRE 16 -1 (-3850 1675)(-3425 1675);
WIRE 16 -1 (-3850 1725)(-3425 1725);
WIRE 16 -1 (-3850 1775)(-3425 1775);
WIRE 16 -1 (-3850 1825)(-3425 1825);
WIRE 16 -1 (-3850 2025)(-3425 2025);
WIRE 16 -1 (-3850 1875)(-3425 1875);
WIRE 16 -1 (-3850 1925)(-3425 1925);
WIRE 16 -1 (-3850 2575)(-3425 2575);
WIRE 16 -1 (-3850 2625)(-3425 2625);
WIRE 16 -1 (-3850 2675)(-3425 2675);
WIRE 16 -1 (-3850 2725)(-3425 2725);
WIRE 16 -1 (-3850 2775)(-3425 2775);
WIRE 16 -1 (-3850 2825)(-3425 2825);
WIRE 16 -1 (-3850 2925)(-3425 2925);
WIRE 16 -1 (-3850 2975)(-3425 2975);
WIRE 16 -1 (-3850 3025)(-3425 3025);
WIRE 16 -1 (-3850 2075)(-3425 2075);
WIRE 16 -1 (-3850 2475)(-3425 2475);
WIRE 16 -1 (-3850 2125)(-3425 2125);
WIRE 16 -1 (-3850 2525)(-3425 2525);
WIRE 16 -1 (-3850 2175)(-3425 2175);
WIRE 16 -1 (-3850 2225)(-3425 2225);
WIRE 16 -1 (-3850 2275)(-3425 2275);
WIRE 16 -1 (-3850 2325)(-3425 2325);
WIRE 16 -1 (-3850 2375)(-3425 2375);
WIRE 16 -1 (-3850 3875)(-3425 3875);
WIRE 16 -1 (-3850 3175)(-3425 3175);
WIRE 16 -1 (-3850 3925)(-3425 3925);
WIRE 16 -1 (-3850 3225)(-3425 3225);
WIRE 16 -1 (-3850 3975)(-3425 3975);
WIRE 16 -1 (-3850 3275)(-3425 3275);
WIRE 16 -1 (-3850 4025)(-3425 4025);
WIRE 16 -1 (-3850 3375)(-3425 3375);
WIRE 16 -1 (-3850 4075)(-3425 4075);
WIRE 16 -1 (-3850 3425)(-3425 3425);
WIRE 16 -1 (-3850 3475)(-3425 3475);
WIRE 16 -1 (-3850 3525)(-3425 3525);
WIRE 16 -1 (-3850 3575)(-3425 3575);
WIRE 16 -1 (-3850 3625)(-3425 3625);
WIRE 16 -1 (-3850 3075)(-3425 3075);
WIRE 16 -1 (-3850 3675)(-3425 3675);
WIRE 16 -1 (-3850 3725)(-3425 3725);
WIRE 16 -1 (-3850 3825)(-3425 3825);
WIRE 16 -1 (-3850 3125)(-3425 3125);
WIRE 16 -1 (-3850 4925)(-3425 4925);
WIRE 16 -1 (-3850 4125)(-3425 4125);
WIRE 16 -1 (-3850 4975)(-3425 4975);
WIRE 16 -1 (-3850 4375)(-3425 4375);
WIRE 16 -1 (-3850 4175)(-3425 4175);
WIRE 16 -1 (-3850 5025)(-3425 5025);
WIRE 16 -1 (-3850 4425)(-3425 4425);
WIRE 16 -1 (-3850 5075)(-3425 5075);
WIRE 16 -1 (-3850 4475)(-3425 4475);
WIRE 16 -1 (-3850 4525)(-3425 4525);
WIRE 16 -1 (-3850 4575)(-3425 4575);
WIRE 16 -1 (-3850 4625)(-3425 4625);
WIRE 16 -1 (-3850 4725)(-3425 4725);
WIRE 16 -1 (-3850 4775)(-3425 4775);
WIRE 16 -1 (-3850 4825)(-3425 4825);
WIRE 16 -1 (-3850 4875)(-3425 4875);
WIRE 16 -1 (-3850 4275)(-3425 4275);
WIRE 16 -1 (-3850 4325)(-3425 4325);
WIRE 16 -1 (-3850 5625)(-3425 5625);
WIRE 16 -1 (-3850 5675)(-3425 5675);
WIRE 16 -1 (-3850 5725)(-3425 5725);
WIRE 16 -1 (-3850 5775)(-3425 5775);
WIRE 16 -1 (-3850 5825)(-3425 5825);
WIRE 16 -1 (-3850 5875)(-3425 5875);
WIRE 16 -1 (-3850 5925)(-3425 5925);
WIRE 16 -1 (-3850 5975)(-3425 5975);
WIRE 16 -1 (-3850 5175)(-3425 5175);
WIRE 16 -1 (-3850 5225)(-3425 5225);
WIRE 16 -1 (-3850 5275)(-3425 5275);
WIRE 16 -1 (-3850 5325)(-3425 5325);
WIRE 16 -1 (-3850 5375)(-3425 5375);
WIRE 16 -1 (-3850 5425)(-3425 5425);
WIRE 16 -1 (-3850 5475)(-3425 5475);
WIRE 16 -1 (-3850 5525)(-3425 5525);
QUIT
